FILE_TYPE = MACRO_DRAWING;
SET COLOR_WIRE YELLOW;
SET COLOR_PROP MONO;
SET COLOR_DOT WHITE;
SET COLOR_ARC YELLOW;
SET COLOR_BODY GREEN;
SET COLOR_NOTE MONO;
SET PROP_DISPLAY VALUE;
SET PAGE_NUMBER P200;
FORCEADD TTL1G126_A..1
(-2900 2225);
FORCEPROP 2 LAST CDS_LIB mstr_ttl
J 0
(-2900 2225);
PAINT ORANGE (-2900 2225);
DISPLAY INVISIBLE (-2900 2225);
FORCEPROP 1 LAST PACK_TYPE SOT
J 0
(-2950 2475);
DISPLAY 0.978723 (-2950 2475);
PAINT SKYBLUE (-2950 2475);
DISPLAY INVISIBLE (-2950 2475);
FORCEPROP 2 LAST CDS_LOCATION U1D1
J 0
(-2950 2425);
DISPLAY 0.617021 (-2950 2425);
PAINT AQUA (-2950 2425);
DISPLAY INVISIBLE (-2950 2425);
FORCEPROP 1 LAST PATH I103
J 2
(-3005 2325);
DISPLAY 0.978723 (-3005 2325);
PAINT GREEN (-3005 2325);
DISPLAY INVISIBLE (-3005 2325);
FORCEPROP 2 LAST ROOM HOT_SWAP
J 0
(-2950 2475);
PAINT MONO (-2950 2475);
DISPLAY INVISIBLE (-2950 2475);
FORCEPROP 2 LAST SEC_TYPE SOT
J 0
(-2950 2575);
DISPLAY 1.021277 (-2950 2575);
PAINT ORANGE (-2950 2575);
DISPLAY INVISIBLE (-2950 2575);
FORCEPROP 2 LAST SEC 1
J 0
(-2950 2575);
DISPLAY 0.680851 (-2950 2575);
PAINT MONO (-2950 2575);
DISPLAY INVISIBLE (-2950 2575);
FORCEPROP 1 LAST PART_NUMBER A79322-001
J 0
(-3275 2135);
DISPLAY 0.617021 (-3275 2135);
PAINT BLUE (-3275 2135);
FORCEPROP 1 LAST VALUE 74HC1G126
J 0
(-2950 2325);
DISPLAY 0.617021 (-2950 2325);
PAINT SKYBLUE (-2950 2325);
FORCEPROP 1 LASTPIN (-3050 2225) $PN 2
J 2
(-3025 2235);
DISPLAY 0.617021 (-3025 2235);
PAINT WHITE (-3025 2235);
FORCEPROP 1 LASTPIN (-2750 2225) $PN 4
J 0
(-2785 2235);
DISPLAY 0.617021 (-2785 2235);
PAINT WHITE (-2785 2235);
FORCEPROP 1 LASTPIN (-2900 2125) $PN 1
J 0
(-2895 2075);
DISPLAY 0.617021 (-2895 2075);
PAINT WHITE (-2895 2075);
FORCEPROP 1 LAST LOCATION U1D1
J 0
(-2950 2425);
DISPLAY 0.617021 (-2950 2425);
PAINT AQUA (-2950 2425);
FORCEPROP 1 LAST MATERIAL IC
J 0
(-2950 2375);
DISPLAY 0.617021 (-2950 2375);
PAINT SKYBLUE (-2950 2375);
FORCEPROP 1 LAST POWER_GROUP GND=GND
J 0
(-3225 2085);
DISPLAY 0.617021 (-3225 2085);
PAINT ORANGE (-3225 2085);
FORCEPROP 1 LAST POWER_GROUP VCC=P3V3_STBY
J 0
(-3250 2050);
DISPLAY 0.617021 (-3250 2050);
PAINT ORANGE (-3250 2050);
FORCEADD AGND0..1
(-1650 -475);
FORCEPROP 3 LASTPIN (-1650 -425) SIG_NAME AGND_HSC\g
J 0
(-1640 -415);
DISPLAY 0.659574 (-1640 -415);
PAINT MONO (-1640 -415);
DISPLAY INVISIBLE (-1640 -415);
FORCEPROP 1 LAST BODY_TYPE PLUMBING
J 0
(-1695 -518);
DISPLAY 0.340426 (-1695 -518);
PAINT GREEN (-1695 -518);
DISPLAY INVISIBLE (-1695 -518);
FORCEPROP 2 LAST ROOM VR_P3V3
J 0
(-1675 -500);
PAINT ORANGE (-1675 -500);
DISPLAY INVISIBLE (-1675 -500);
FORCEPROP 1 LAST PATH I106
J 0
(-1575 -475);
DISPLAY 0.872340 (-1575 -475);
PAINT AQUA (-1575 -475);
DISPLAY INVISIBLE (-1575 -475);
FORCEPROP 2 LAST BOM_COST MIO_VRD_MAIN
J 0
(-1625 -500);
PAINT ORANGE (-1625 -500);
DISPLAY INVISIBLE (-1625 -500);
FORCEPROP 2 LAST CDS_LIB mstr_symbols
J 0
(-1650 -475);
PAINT ORANGE (-1650 -475);
DISPLAY INVISIBLE (-1650 -475);
FORCEPROP 1 LAST VOLTAGE 0
J 0
(-1650 -475);
PAINT SKYBLUE (-1650 -475);
DISPLAY INVISIBLE (-1650 -475);
FORCEPROP 1 LAST HDL_POWER AGND_HSC
J 1
(-1650 -525);
DISPLAY 0.617021 (-1650 -525);
PAINT GREEN (-1650 -525);
FORCEADD RES..2
(-1650 250);
FORCEPROP 2 LAST CDS_LIB mstr_discrete
J 0
(-1650 250);
PAINT ORANGE (-1650 250);
DISPLAY INVISIBLE (-1650 250);
FORCEPROP 2 LAST CDS_LOCATION R9P13
J 0
(-1605 375);
DISPLAY 0.617021 (-1605 375);
PAINT AQUA (-1605 375);
DISPLAY INVISIBLE (-1605 375);
FORCEPROP 2 LAST ROOM HOT_SWAP
J 0
(-1600 425);
PAINT MONO (-1600 425);
DISPLAY INVISIBLE (-1600 425);
FORCEPROP 1 LAST PATH I107
J 0
(-1600 425);
DISPLAY 0.978723 (-1600 425);
PAINT WHITE (-1600 425);
DISPLAY INVISIBLE (-1600 425);
FORCEPROP 2 LAST SEC 1
J 0
(-1600 475);
DISPLAY 0.680851 (-1600 475);
PAINT MONO (-1600 475);
DISPLAY INVISIBLE (-1600 475);
FORCEPROP 2 LAST SEC_TYPE 0402
J 0
(-1600 475);
DISPLAY 1.021277 (-1600 475);
PAINT ORANGE (-1600 475);
DISPLAY INVISIBLE (-1600 475);
FORCEPROP 1 LAST WATTAGE 1/16W
J 0
(-1610 225);
DISPLAY 0.617021 (-1610 225);
PAINT SKYBLUE (-1610 225);
FORCEPROP 1 LAST VALUE 274K
J 0
(-1605 325);
DISPLAY 0.617021 (-1605 325);
PAINT SKYBLUE (-1605 325);
FORCEPROP 1 LASTPIN (-1650 350) $PN 1
J 0
(-1645 312);
DISPLAY 0.617021 (-1645 312);
PAINT ORANGE (-1645 312);
FORCEPROP 1 LASTPIN (-1650 150) $PN 2
J 0
(-1645 160);
DISPLAY 0.617021 (-1645 160);
PAINT ORANGE (-1645 160);
FORCEPROP 1 LAST LOCATION R9P13
J 0
(-1605 375);
DISPLAY 0.617021 (-1605 375);
PAINT AQUA (-1605 375);
FORCEPROP 1 LAST MATERIAL CHIP
J 0
(-1610 175);
DISPLAY 0.617021 (-1610 175);
PAINT SKYBLUE (-1610 175);
FORCEPROP 1 LAST PACK_TYPE 0402
J 0
(-1485 200);
DISPLAY 0.617021 (-1485 200);
PAINT SKYBLUE (-1485 200);
FORCEPROP 1 LAST TOLERANCE 1.0%
J 0
(-1605 275);
DISPLAY 0.617021 (-1605 275);
PAINT SKYBLUE (-1605 275);
FORCEPROP 1 LAST PART_NUMBER G21796-331
J 0
(-1610 125);
DISPLAY 0.617021 (-1610 125);
PAINT BLUE (-1610 125);
FORCEADD RES..2
(-1650 -150);
FORCEPROP 2 LAST ROOM HOT_SWAP
J 0
(-1600 25);
PAINT MONO (-1600 25);
DISPLAY INVISIBLE (-1600 25);
FORCEPROP 1 LAST PATH I108
J 0
(-1600 25);
DISPLAY 0.978723 (-1600 25);
PAINT WHITE (-1600 25);
DISPLAY INVISIBLE (-1600 25);
FORCEPROP 2 LAST SEC 1
J 0
(-1600 75);
DISPLAY 0.680851 (-1600 75);
PAINT MONO (-1600 75);
DISPLAY INVISIBLE (-1600 75);
FORCEPROP 2 LAST SEC_TYPE 0402
J 0
(-1600 75);
DISPLAY 1.021277 (-1600 75);
PAINT ORANGE (-1600 75);
DISPLAY INVISIBLE (-1600 75);
FORCEPROP 2 LAST CDS_LOCATION R9P11
J 0
(-1605 -25);
DISPLAY 0.617021 (-1605 -25);
PAINT AQUA (-1605 -25);
DISPLAY INVISIBLE (-1605 -25);
FORCEPROP 2 LAST CDS_LIB mstr_discrete
J 0
(-1650 -150);
PAINT ORANGE (-1650 -150);
DISPLAY INVISIBLE (-1650 -150);
FORCEPROP 1 LAST WATTAGE 1/16W
J 0
(-1610 -175);
DISPLAY 0.617021 (-1610 -175);
PAINT SKYBLUE (-1610 -175);
FORCEPROP 1 LAST MATERIAL CHIP
J 0
(-1610 -225);
DISPLAY 0.617021 (-1610 -225);
PAINT SKYBLUE (-1610 -225);
FORCEPROP 1 LAST PART_NUMBER G21796-016
J 0
(-1610 -275);
DISPLAY 0.617021 (-1610 -275);
PAINT BLUE (-1610 -275);
FORCEPROP 1 LAST LOCATION R9P11
J 0
(-1605 -25);
DISPLAY 0.617021 (-1605 -25);
PAINT AQUA (-1605 -25);
FORCEPROP 1 LASTPIN (-1650 -50) $PN 1
J 0
(-1645 -88);
DISPLAY 0.617021 (-1645 -88);
PAINT ORANGE (-1645 -88);
FORCEPROP 1 LAST TOLERANCE 1%
J 0
(-1605 -125);
DISPLAY 0.617021 (-1605 -125);
PAINT SKYBLUE (-1605 -125);
FORCEPROP 1 LAST VALUE 10.0K
J 0
(-1605 -75);
DISPLAY 0.617021 (-1605 -75);
PAINT SKYBLUE (-1605 -75);
FORCEPROP 1 LAST PACK_TYPE 0402
J 0
(-1610 -325);
DISPLAY 0.617021 (-1610 -325);
PAINT SKYBLUE (-1610 -325);
FORCEPROP 1 LASTPIN (-1650 -250) $PN 2
J 0
(-1645 -240);
DISPLAY 0.617021 (-1645 -240);
PAINT ORANGE (-1645 -240);
FORCEADD P12V_STBY..1
(-1650 525);
FORCEPROP 3 LASTPIN (-1650 475) SIG_NAME P12V_STBY\g
J 0
(-1640 485);
DISPLAY 0.659574 (-1640 485);
PAINT MONO (-1640 485);
DISPLAY INVISIBLE (-1640 485);
FORCEPROP 1 LAST HDL_POWER P12V_STBY
J 0
(-1950 400);
DISPLAY 0.872340 (-1950 400);
PAINT ORANGE (-1950 400);
DISPLAY INVISIBLE (-1950 400);
FORCEPROP 1 LAST BODY_TYPE PLUMBING
J 0
(-1695 482);
DISPLAY 0.340426 (-1695 482);
PAINT GREEN (-1695 482);
DISPLAY INVISIBLE (-1695 482);
FORCEPROP 1 LAST VOLTAGE 12.0V
J 0
(-1695 482);
DISPLAY 0.340426 (-1695 482);
PAINT SKYBLUE (-1695 482);
DISPLAY INVISIBLE (-1695 482);
FORCEPROP 1 LAST SIZE 1B
J 0
(-1605 547);
DISPLAY 0.340426 (-1605 547);
PAINT GREEN (-1605 547);
DISPLAY INVISIBLE (-1605 547);
FORCEPROP 1 LAST PATH I109
J 0
(-1605 527);
DISPLAY 0.340426 (-1605 527);
PAINT GREEN (-1605 527);
DISPLAY INVISIBLE (-1605 527);
FORCEPROP 2 LAST CDS_LIB mstr_symbols
J 0
(-1650 525);
PAINT ORANGE (-1650 525);
DISPLAY INVISIBLE (-1650 525);
FORCEADD GND..1
(-3075 -475);
FORCEPROP 3 LASTPIN (-3075 -425) SIG_NAME GND\g
J 0
(-3065 -415);
DISPLAY 0.659574 (-3065 -415);
PAINT MONO (-3065 -415);
DISPLAY INVISIBLE (-3065 -415);
FORCEPROP 1 LAST SIZE 1B
J 0
(-3000 -525);
DISPLAY 0.872340 (-3000 -525);
PAINT AQUA (-3000 -525);
DISPLAY INVISIBLE (-3000 -525);
FORCEPROP 1 LAST PATH I114
J 0
(-3000 -475);
DISPLAY 0.872340 (-3000 -475);
PAINT AQUA (-3000 -475);
DISPLAY INVISIBLE (-3000 -475);
FORCEPROP 2 LAST CDS_LIB mstr_symbols
J 0
(-3075 -475);
PAINT ORANGE (-3075 -475);
DISPLAY INVISIBLE (-3075 -475);
FORCEPROP 1 LAST VOLTAGE 0.0V
J 0
(-3120 -518);
DISPLAY 0.340426 (-3120 -518);
PAINT SKYBLUE (-3120 -518);
DISPLAY INVISIBLE (-3120 -518);
FORCEPROP 1 LAST BODY_TYPE PLUMBING
J 0
(-3120 -518);
DISPLAY 0.340426 (-3120 -518);
PAINT GREEN (-3120 -518);
DISPLAY INVISIBLE (-3120 -518);
FORCEPROP 1 LAST HDL_POWER GND
J 0
(-3075 -325);
DISPLAY 0.872340 (-3075 -325);
PAINT GREEN (-3075 -325);
DISPLAY INVISIBLE (-3075 -325);
FORCEADD OFFPAGE..2
(-975 2225);
FORCEPROP 2 LAST CDS_LIB mstr_standard
J 0
(-975 2225);
PAINT ORANGE (-975 2225);
DISPLAY INVISIBLE (-975 2225);
FORCEPROP 2 LAST PATH I118
J 0
(-800 2300);
DISPLAY 1.021277 (-800 2300);
PAINT ORANGE (-800 2300);
DISPLAY INVISIBLE (-800 2300);
FORCEPROP 1 LAST OFFPAGE TRUE
J 0
(-650 2100);
DISPLAY 0.872340 (-650 2100);
PAINT GREEN (-650 2100);
DISPLAY INVISIBLE (-650 2100);
FORCEPROP 1 LAST COMMENT_BODY TRUE
J 0
(-1020 2130);
DISPLAY 0.872340 (-1020 2130);
PAINT GREEN (-1020 2130);
DISPLAY INVISIBLE (-1020 2130);
FORCEPROP 2 LAST $XR0 170 
J 0
(-786 2225);
DISPLAY 0.638298 (-786 2225);
PAINT MONO (-786 2225);
FORCEADD OFFPAGE..2
(2575 -50);
FORCEPROP 2 LAST PATH I121
J 0
(2750 25);
DISPLAY 1.021277 (2750 25);
PAINT ORANGE (2750 25);
DISPLAY INVISIBLE (2750 25);
FORCEPROP 2 LAST CDS_LIB mstr_standard
J 0
(2575 -50);
PAINT ORANGE (2575 -50);
DISPLAY INVISIBLE (2575 -50);
FORCEPROP 1 LAST OFFPAGE TRUE
J 0
(2900 -175);
DISPLAY 0.872340 (2900 -175);
PAINT GREEN (2900 -175);
DISPLAY INVISIBLE (2900 -175);
FORCEPROP 1 LAST COMMENT_BODY TRUE
J 0
(2530 -145);
DISPLAY 0.872340 (2530 -145);
PAINT GREEN (2530 -145);
DISPLAY INVISIBLE (2530 -145);
FORCEPROP 2 LAST $XR2 170 
J 0
(2764 -86);
DISPLAY 0.638298 (2764 -86);
PAINT MONO (2764 -86);
FORCEPROP 2 LAST $XR1 145 
J 0
(2884 -50);
DISPLAY 0.638298 (2884 -50);
PAINT MONO (2884 -50);
FORCEPROP 2 LAST $XR0 120 
J 0
(2764 -50);
DISPLAY 0.638298 (2764 -50);
PAINT MONO (2764 -50);
FORCEADD OFFPAGE..2
(2550 675);
FORCEPROP 2 LAST PATH I134
J 0
(2725 750);
DISPLAY 1.021277 (2725 750);
PAINT ORANGE (2725 750);
DISPLAY INVISIBLE (2725 750);
FORCEPROP 2 LAST CDS_LIB mstr_standard
J 0
(2550 675);
PAINT ORANGE (2550 675);
DISPLAY INVISIBLE (2550 675);
FORCEPROP 1 LAST OFFPAGE TRUE
J 0
(2875 550);
DISPLAY 0.872340 (2875 550);
PAINT GREEN (2875 550);
DISPLAY INVISIBLE (2875 550);
FORCEPROP 1 LAST COMMENT_BODY TRUE
J 0
(2505 580);
DISPLAY 0.872340 (2505 580);
PAINT GREEN (2505 580);
DISPLAY INVISIBLE (2505 580);
FORCEPROP 2 LAST $XR0 161 
J 0
(2739 675);
DISPLAY 0.638298 (2739 675);
PAINT MONO (2739 675);
FORCEADD OFFPAGE..2
(2525 900);
FORCEPROP 2 LAST PATH I135
J 0
(2700 975);
DISPLAY 1.021277 (2700 975);
PAINT ORANGE (2700 975);
DISPLAY INVISIBLE (2700 975);
FORCEPROP 2 LAST CDS_LIB mstr_standard
J 0
(2525 900);
PAINT ORANGE (2525 900);
DISPLAY INVISIBLE (2525 900);
FORCEPROP 1 LAST OFFPAGE TRUE
J 0
(2850 775);
DISPLAY 0.872340 (2850 775);
PAINT GREEN (2850 775);
DISPLAY INVISIBLE (2850 775);
FORCEPROP 1 LAST COMMENT_BODY TRUE
J 0
(2480 805);
DISPLAY 0.872340 (2480 805);
PAINT GREEN (2480 805);
DISPLAY INVISIBLE (2480 805);
FORCEPROP 2 LAST $XR0 191 
J 0
(2714 900);
DISPLAY 0.638298 (2714 900);
PAINT MONO (2714 900);
FORCEADD P12V_STBY..1
(-1975 1025);
FORCEPROP 3 LASTPIN (-1975 975) SIG_NAME P12V_STBY\g
J 0
(-1965 985);
DISPLAY 0.659574 (-1965 985);
PAINT MONO (-1965 985);
DISPLAY INVISIBLE (-1965 985);
FORCEPROP 1 LAST PATH I144
J 0
(-1930 1027);
DISPLAY 0.340426 (-1930 1027);
PAINT GREEN (-1930 1027);
DISPLAY INVISIBLE (-1930 1027);
FORCEPROP 2 LAST CDS_LIB mstr_symbols
J 0
(-1975 1025);
PAINT ORANGE (-1975 1025);
DISPLAY INVISIBLE (-1975 1025);
FORCEPROP 1 LAST SIZE 1B
J 0
(-1930 1047);
DISPLAY 0.340426 (-1930 1047);
PAINT GREEN (-1930 1047);
DISPLAY INVISIBLE (-1930 1047);
FORCEPROP 1 LAST VOLTAGE 12.0V
J 0
(-2020 982);
DISPLAY 0.340426 (-2020 982);
PAINT SKYBLUE (-2020 982);
DISPLAY INVISIBLE (-2020 982);
FORCEPROP 1 LAST BODY_TYPE PLUMBING
J 0
(-2020 982);
DISPLAY 0.340426 (-2020 982);
PAINT GREEN (-2020 982);
DISPLAY INVISIBLE (-2020 982);
FORCEPROP 1 LAST HDL_POWER P12V_STBY
J 0
(-2275 900);
DISPLAY 0.872340 (-2275 900);
PAINT ORANGE (-2275 900);
DISPLAY INVISIBLE (-2275 900);
FORCEADD RES..2
(-1975 800);
FORCEPROP 2 LAST SEC_TYPE 0402
J 0
(-1925 1025);
DISPLAY 1.021277 (-1925 1025);
PAINT ORANGE (-1925 1025);
DISPLAY INVISIBLE (-1925 1025);
FORCEPROP 2 LAST SEC 1
J 0
(-1925 1025);
DISPLAY 0.680851 (-1925 1025);
PAINT MONO (-1925 1025);
DISPLAY INVISIBLE (-1925 1025);
FORCEPROP 2 LAST CDS_LOCATION R9P7
J 0
(-1930 925);
DISPLAY 0.617021 (-1930 925);
PAINT AQUA (-1930 925);
DISPLAY INVISIBLE (-1930 925);
FORCEPROP 1 LAST PATH I145
J 0
(-1925 975);
DISPLAY 0.978723 (-1925 975);
PAINT WHITE (-1925 975);
DISPLAY INVISIBLE (-1925 975);
FORCEPROP 2 LAST ROOM HOT_SWAP
J 0
(-1925 975);
PAINT MONO (-1925 975);
DISPLAY INVISIBLE (-1925 975);
FORCEPROP 2 LAST CDS_LIB mstr_discrete
J 0
(-1975 800);
PAINT ORANGE (-1975 800);
DISPLAY INVISIBLE (-1975 800);
FORCEPROP 1 LAST VALUE 249K
J 0
(-1930 875);
DISPLAY 0.617021 (-1930 875);
PAINT SKYBLUE (-1930 875);
FORCEPROP 1 LAST PACK_TYPE 0402
J 0
(-1785 775);
DISPLAY 0.617021 (-1785 775);
PAINT SKYBLUE (-1785 775);
FORCEPROP 1 LAST LOCATION R9P7
J 0
(-1930 925);
DISPLAY 0.617021 (-1930 925);
PAINT AQUA (-1930 925);
FORCEPROP 1 LASTPIN (-1975 900) $PN 1
J 0
(-1970 862);
DISPLAY 0.617021 (-1970 862);
PAINT ORANGE (-1970 862);
FORCEPROP 1 LASTPIN (-1975 700) $PN 2
J 0
(-1970 710);
DISPLAY 0.617021 (-1970 710);
PAINT ORANGE (-1970 710);
FORCEPROP 1 LAST WATTAGE 1/16W
J 0
(-1935 775);
DISPLAY 0.617021 (-1935 775);
PAINT SKYBLUE (-1935 775);
FORCEPROP 1 LAST MATERIAL CHIP
J 0
(-1935 725);
DISPLAY 0.617021 (-1935 725);
PAINT SKYBLUE (-1935 725);
FORCEPROP 1 LAST PART_NUMBER G21796-189
J 0
(-1935 675);
DISPLAY 0.617021 (-1935 675);
PAINT BLUE (-1935 675);
FORCEPROP 1 LAST TOLERANCE 1.0%
J 0
(-1930 825);
DISPLAY 0.617021 (-1930 825);
PAINT SKYBLUE (-1930 825);
FORCEADD RES..2
(-1975 375);
FORCEPROP 2 LAST SEC_TYPE 0402
J 0
(-1925 600);
DISPLAY 1.021277 (-1925 600);
PAINT ORANGE (-1925 600);
DISPLAY INVISIBLE (-1925 600);
FORCEPROP 2 LAST SEC 1
J 0
(-1925 600);
DISPLAY 0.680851 (-1925 600);
PAINT MONO (-1925 600);
DISPLAY INVISIBLE (-1925 600);
FORCEPROP 1 LAST PATH I146
J 0
(-1925 550);
DISPLAY 0.978723 (-1925 550);
PAINT WHITE (-1925 550);
DISPLAY INVISIBLE (-1925 550);
FORCEPROP 2 LAST ROOM HOT_SWAP
J 0
(-1925 550);
PAINT MONO (-1925 550);
DISPLAY INVISIBLE (-1925 550);
FORCEPROP 2 LAST CDS_LOCATION R9P9
J 0
(-1930 500);
DISPLAY 0.617021 (-1930 500);
PAINT AQUA (-1930 500);
DISPLAY INVISIBLE (-1930 500);
FORCEPROP 2 LAST CDS_LIB mstr_discrete
J 0
(-1975 375);
PAINT ORANGE (-1975 375);
DISPLAY INVISIBLE (-1975 375);
FORCEPROP 1 LAST PART_NUMBER G21796-016
J 0
(-1935 250);
DISPLAY 0.617021 (-1935 250);
PAINT BLUE (-1935 250);
FORCEPROP 1 LAST PACK_TYPE 0402
J 0
(-1935 200);
DISPLAY 0.617021 (-1935 200);
PAINT SKYBLUE (-1935 200);
FORCEPROP 1 LASTPIN (-1975 475) $PN 1
J 0
(-1970 437);
DISPLAY 0.617021 (-1970 437);
PAINT ORANGE (-1970 437);
FORCEPROP 1 LASTPIN (-1975 275) $PN 2
J 0
(-1970 285);
DISPLAY 0.617021 (-1970 285);
PAINT ORANGE (-1970 285);
FORCEPROP 1 LAST VALUE 10.0K
J 0
(-1930 450);
DISPLAY 0.617021 (-1930 450);
PAINT SKYBLUE (-1930 450);
FORCEPROP 1 LAST TOLERANCE 1%
J 0
(-1930 400);
DISPLAY 0.617021 (-1930 400);
PAINT SKYBLUE (-1930 400);
FORCEPROP 1 LAST MATERIAL CHIP
J 0
(-1935 300);
DISPLAY 0.617021 (-1935 300);
PAINT SKYBLUE (-1935 300);
FORCEPROP 1 LAST LOCATION R9P9
J 0
(-1930 500);
DISPLAY 0.617021 (-1930 500);
PAINT AQUA (-1930 500);
FORCEPROP 1 LAST WATTAGE 1/16W
J 0
(-1935 350);
DISPLAY 0.617021 (-1935 350);
PAINT SKYBLUE (-1935 350);
FORCEADD AGND0..1
(-1975 25);
FORCEPROP 3 LASTPIN (-1975 75) SIG_NAME AGND_HSC\g
J 0
(-1965 85);
DISPLAY 0.659574 (-1965 85);
PAINT MONO (-1965 85);
DISPLAY INVISIBLE (-1965 85);
FORCEPROP 1 LAST VOLTAGE 0
J 0
(-1975 25);
PAINT SKYBLUE (-1975 25);
DISPLAY INVISIBLE (-1975 25);
FORCEPROP 2 LAST CDS_LIB mstr_symbols
J 0
(-1975 25);
PAINT ORANGE (-1975 25);
DISPLAY INVISIBLE (-1975 25);
FORCEPROP 1 LAST PATH I147
J 0
(-1900 25);
DISPLAY 0.872340 (-1900 25);
PAINT AQUA (-1900 25);
DISPLAY INVISIBLE (-1900 25);
FORCEPROP 2 LAST BOM_COST MIO_VRD_MAIN
J 0
(-1950 0);
PAINT ORANGE (-1950 0);
DISPLAY INVISIBLE (-1950 0);
FORCEPROP 2 LAST ROOM VR_P3V3
J 0
(-2000 0);
PAINT ORANGE (-2000 0);
DISPLAY INVISIBLE (-2000 0);
FORCEPROP 1 LAST BODY_TYPE PLUMBING
J 0
(-2020 -18);
DISPLAY 0.340426 (-2020 -18);
PAINT GREEN (-2020 -18);
DISPLAY INVISIBLE (-2020 -18);
FORCEPROP 1 LAST HDL_POWER AGND_HSC
J 1
(-1975 -25);
DISPLAY 0.617021 (-1975 -25);
PAINT GREEN (-1975 -25);
FORCEADD RES..2
(600 1100);
FORCEPROP 2 LAST SEC_TYPE 0402
J 0
(650 1325);
DISPLAY 1.021277 (650 1325);
PAINT ORANGE (650 1325);
DISPLAY INVISIBLE (650 1325);
FORCEPROP 2 LAST SEC 1
J 0
(650 1325);
DISPLAY 0.680851 (650 1325);
PAINT MONO (650 1325);
DISPLAY INVISIBLE (650 1325);
FORCEPROP 1 LAST PATH I149
J 0
(650 1275);
DISPLAY 0.978723 (650 1275);
PAINT WHITE (650 1275);
DISPLAY INVISIBLE (650 1275);
FORCEPROP 2 LAST ROOM HOT_SWAP
J 0
(650 1275);
PAINT MONO (650 1275);
DISPLAY INVISIBLE (650 1275);
FORCEPROP 2 LAST CDS_LOCATION R9P6
J 0
(645 1225);
DISPLAY 0.617021 (645 1225);
PAINT AQUA (645 1225);
DISPLAY INVISIBLE (645 1225);
FORCEPROP 2 LAST CDS_LIB mstr_discrete
J 0
(600 1100);
PAINT ORANGE (600 1100);
DISPLAY INVISIBLE (600 1100);
FORCEPROP 1 LAST MATERIAL CHIP
J 0
(640 1025);
DISPLAY 0.617021 (640 1025);
PAINT SKYBLUE (640 1025);
FORCEPROP 1 LAST WATTAGE 1/16W
J 0
(640 1075);
DISPLAY 0.617021 (640 1075);
PAINT SKYBLUE (640 1075);
FORCEPROP 1 LAST VALUE 10.0K
J 0
(645 1175);
DISPLAY 0.617021 (645 1175);
PAINT SKYBLUE (645 1175);
FORCEPROP 1 LAST LOCATION R9P6
J 0
(645 1225);
DISPLAY 0.617021 (645 1225);
PAINT AQUA (645 1225);
FORCEPROP 1 LAST PART_NUMBER G21796-016
J 0
(640 975);
DISPLAY 0.617021 (640 975);
PAINT BLUE (640 975);
FORCEPROP 1 LAST TOLERANCE 1%
J 0
(645 1125);
DISPLAY 0.617021 (645 1125);
PAINT SKYBLUE (645 1125);
FORCEPROP 1 LASTPIN (600 1200) $PN 1
J 0
(605 1162);
DISPLAY 0.617021 (605 1162);
PAINT ORANGE (605 1162);
FORCEPROP 1 LASTPIN (600 1000) $PN 2
J 0
(605 1010);
DISPLAY 0.617021 (605 1010);
PAINT ORANGE (605 1010);
FORCEPROP 1 LAST PACK_TYPE 0402
J 0
(640 925);
DISPLAY 0.617021 (640 925);
PAINT SKYBLUE (640 925);
FORCEADD P3V3_STBY..1
(600 1400);
FORCEPROP 3 LASTPIN (600 1350) SIG_NAME P3V3_STBY\g
J 0
(610 1360);
DISPLAY 0.659574 (610 1360);
PAINT MONO (610 1360);
DISPLAY INVISIBLE (610 1360);
FORCEPROP 1 LAST VOLTAGE +3.3V
J 0
(800 1550);
DISPLAY 1.021277 (800 1550);
PAINT SKYBLUE (800 1550);
DISPLAY INVISIBLE (800 1550);
FORCEPROP 1 LAST SIZE 1B
J 0
(645 1422);
DISPLAY 0.340426 (645 1422);
PAINT GREEN (645 1422);
DISPLAY INVISIBLE (645 1422);
FORCEPROP 2 LAST CDS_LIB mstr_symbols
J 0
(600 1400);
PAINT ORANGE (600 1400);
DISPLAY INVISIBLE (600 1400);
FORCEPROP 1 LAST PATH I150
J 0
(645 1402);
DISPLAY 0.340426 (645 1402);
PAINT GREEN (645 1402);
DISPLAY INVISIBLE (645 1402);
FORCEPROP 1 LAST BODY_TYPE PLUMBING
J 0
(555 1357);
DISPLAY 0.340426 (555 1357);
PAINT GREEN (555 1357);
DISPLAY INVISIBLE (555 1357);
FORCEPROP 1 LAST HDL_POWER P3V3_STBY
J 0
(300 1275);
DISPLAY 0.872340 (300 1275);
PAINT ORANGE (300 1275);
DISPLAY INVISIBLE (300 1275);
FORCEADD OFFPAGE..2
(-975 2600);
FORCEPROP 2 LAST CDS_LIB mstr_standard
J 0
(-975 2600);
PAINT MONO (-975 2600);
DISPLAY INVISIBLE (-975 2600);
FORCEPROP 2 LAST PATH I153
J 0
(-800 2675);
DISPLAY 1.021277 (-800 2675);
PAINT ORANGE (-800 2675);
DISPLAY INVISIBLE (-800 2675);
FORCEPROP 1 LAST OFFPAGE TRUE
J 0
(-650 2475);
DISPLAY 0.872340 (-650 2475);
PAINT GREEN (-650 2475);
DISPLAY INVISIBLE (-650 2475);
FORCEPROP 1 LAST COMMENT_BODY TRUE
J 0
(-1020 2505);
DISPLAY 0.872340 (-1020 2505);
PAINT GREEN (-1020 2505);
DISPLAY INVISIBLE (-1020 2505);
FORCEPROP 2 LAST $XR1 145 
J 0
(-666 2600);
DISPLAY 0.638298 (-666 2600);
PAINT MONO (-666 2600);
FORCEPROP 2 LAST $XR0 120 
J 0
(-786 2600);
DISPLAY 0.638298 (-786 2600);
PAINT MONO (-786 2600);
FORCEADD RES..1
(1350 1875);
FORCEPROP 2 LAST SEC_TYPE 0402
J 0
(1300 2075);
DISPLAY 1.021277 (1300 2075);
PAINT ORANGE (1300 2075);
DISPLAY INVISIBLE (1300 2075);
FORCEPROP 2 LAST SEC 1
J 0
(1300 2075);
DISPLAY 0.680851 (1300 2075);
PAINT MONO (1300 2075);
DISPLAY INVISIBLE (1300 2075);
FORCEPROP 0 LAST ROOM HOT_SWAP
J 0
(1300 2075);
DISPLAY 1.021277 (1300 2075);
PAINT ORANGE (1300 2075);
DISPLAY INVISIBLE (1300 2075);
FORCEPROP 1 LAST PATH I154
J 0
(1300 2025);
DISPLAY 0.978723 (1300 2025);
PAINT WHITE (1300 2025);
DISPLAY INVISIBLE (1300 2025);
FORCEPROP 2 LAST CDS_LOCATION R1D51
J 0
(1300 1925);
DISPLAY 0.617021 (1300 1925);
PAINT AQUA (1300 1925);
DISPLAY INVISIBLE (1300 1925);
FORCEPROP 2 LAST CDS_LIB mstr_discrete
J 0
(1350 1875);
PAINT MONO (1350 1875);
DISPLAY INVISIBLE (1350 1875);
FORCEPROP 1 LAST PART_NUMBER G21796-066
J 0
(1300 1975);
DISPLAY 0.617021 (1300 1975);
PAINT BLUE (1300 1975);
FORCEPROP 1 LASTPIN (1450 1875) $PN 2
J 0
(1412 1887);
DISPLAY 0.617021 (1412 1887);
PAINT ORANGE (1412 1887);
FORCEPROP 1 LAST LOCATION R1D51
J 0
(1300 1925);
DISPLAY 0.617021 (1300 1925);
PAINT AQUA (1300 1925);
FORCEPROP 1 LAST TOLERANCE 1%
J 0
(1425 1825);
DISPLAY 0.617021 (1425 1825);
PAINT SKYBLUE (1425 1825);
FORCEPROP 1 LASTPIN (1250 1875) $PN 1
J 0
(1262 1887);
DISPLAY 0.617021 (1262 1887);
PAINT ORANGE (1262 1887);
FORCEPROP 1 LAST WATTAGE 1/16W
J 2
(1250 1775);
DISPLAY 0.617021 (1250 1775);
PAINT SKYBLUE (1250 1775);
FORCEPROP 1 LAST MATERIAL CHIP
J 0
(1150 1725);
DISPLAY 0.617021 (1150 1725);
PAINT SKYBLUE (1150 1725);
FORCEPROP 1 LAST PACK_TYPE 0402
J 0
(1125 1825);
DISPLAY 0.617021 (1125 1825);
PAINT SKYBLUE (1125 1825);
FORCEPROP 1 LAST VALUE 10.0
J 2
(1375 1825);
DISPLAY 0.617021 (1375 1825);
PAINT SKYBLUE (1375 1825);
FORCEADD CAP..1
(900 1675);
FORCEPROP 2 LAST SEC_TYPE 1206
J 0
(950 1875);
DISPLAY 1.021277 (950 1875);
PAINT ORANGE (950 1875);
DISPLAY INVISIBLE (950 1875);
FORCEPROP 2 LAST SEC 1
J 0
(950 1875);
DISPLAY 0.680851 (950 1875);
PAINT MONO (950 1875);
DISPLAY INVISIBLE (950 1875);
FORCEPROP 1 LAST PATH I155
J 0
(950 1825);
DISPLAY 0.978723 (950 1825);
PAINT WHITE (950 1825);
DISPLAY INVISIBLE (950 1825);
FORCEPROP 2 LAST CDS_LOCATION C1E2
J 0
(950 1775);
DISPLAY 0.617021 (950 1775);
PAINT AQUA (950 1775);
DISPLAY INVISIBLE (950 1775);
FORCEPROP 2 LAST CDS_LIB mstr_discrete
J 0
(900 1675);
PAINT MONO (900 1675);
DISPLAY INVISIBLE (900 1675);
FORCEPROP 1 LAST TOLERANCE 20%
J 0
(950 1625);
DISPLAY 0.617021 (950 1625);
PAINT SKYBLUE (950 1625);
FORCEPROP 1 LAST MATERIAL X7R
J 0
(950 1575);
DISPLAY 0.617021 (950 1575);
PAINT SKYBLUE (950 1575);
FORCEPROP 1 LAST PART_NUMBER 108427-047
J 0
(950 1525);
DISPLAY 0.617021 (950 1525);
PAINT BLUE (950 1525);
FORCEPROP 1 LAST LOCATION C1E2
J 0
(950 1775);
DISPLAY 0.617021 (950 1775);
PAINT AQUA (950 1775);
FORCEPROP 1 LAST VALUE 0.068UF
J 0
(950 1725);
DISPLAY 0.617021 (950 1725);
PAINT SKYBLUE (950 1725);
FORCEPROP 1 LAST VOLTAGE 50V
J 0
(950 1675);
DISPLAY 0.617021 (950 1675);
PAINT SKYBLUE (950 1675);
FORCEPROP 1 LASTPIN (900 1575) $PN 2
J 0
(910 1555);
DISPLAY 0.617021 (910 1555);
PAINT ORANGE (910 1555);
FORCEPROP 1 LASTPIN (900 1775) $PN 1
J 0
(910 1755);
DISPLAY 0.617021 (910 1755);
PAINT ORANGE (910 1755);
FORCEPROP 1 LAST PACK_TYPE 1206
J 0
(950 1475);
DISPLAY 0.617021 (950 1475);
PAINT SKYBLUE (950 1475);
FORCEADD GND..1
(900 1450);
FORCEPROP 3 LASTPIN (900 1500) SIG_NAME GND\g
J 0
(910 1510);
DISPLAY 0.659574 (910 1510);
PAINT MONO (910 1510);
DISPLAY INVISIBLE (910 1510);
FORCEPROP 1 LAST VOLTAGE 0.0V
J 0
(855 1407);
DISPLAY 0.340426 (855 1407);
PAINT SKYBLUE (855 1407);
DISPLAY INVISIBLE (855 1407);
FORCEPROP 2 LAST CDS_LIB mstr_symbols
J 0
(900 1450);
PAINT MONO (900 1450);
DISPLAY INVISIBLE (900 1450);
FORCEPROP 1 LAST SIZE 1B
J 0
(975 1400);
DISPLAY 0.872340 (975 1400);
PAINT AQUA (975 1400);
DISPLAY INVISIBLE (975 1400);
FORCEPROP 1 LAST PATH I156
J 0
(975 1450);
DISPLAY 0.872340 (975 1450);
PAINT AQUA (975 1450);
DISPLAY INVISIBLE (975 1450);
FORCEPROP 1 LAST BODY_TYPE PLUMBING
J 0
(855 1407);
DISPLAY 0.340426 (855 1407);
PAINT GREEN (855 1407);
DISPLAY INVISIBLE (855 1407);
FORCEPROP 1 LAST HDL_POWER GND
J 0
(900 1600);
DISPLAY 0.872340 (900 1600);
PAINT GREEN (900 1600);
DISPLAY INVISIBLE (900 1600);
FORCEADD P3V3_STBY..1
(-1650 2525);
FORCEPROP 3 LASTPIN (-1650 2475) SIG_NAME P3V3_STBY\g
J 0
(-1640 2485);
DISPLAY 0.659574 (-1640 2485);
PAINT MONO (-1640 2485);
DISPLAY INVISIBLE (-1640 2485);
FORCEPROP 2 LAST CDS_LIB mstr_symbols
J 0
(-1650 2525);
PAINT ORANGE (-1650 2525);
DISPLAY INVISIBLE (-1650 2525);
FORCEPROP 1 LAST PATH I157
J 0
(-1605 2527);
DISPLAY 0.340426 (-1605 2527);
PAINT GREEN (-1605 2527);
DISPLAY INVISIBLE (-1605 2527);
FORCEPROP 1 LAST SIZE 1B
J 0
(-1605 2547);
DISPLAY 0.340426 (-1605 2547);
PAINT GREEN (-1605 2547);
DISPLAY INVISIBLE (-1605 2547);
FORCEPROP 1 LAST VOLTAGE +3.3V
J 0
(-1450 2675);
DISPLAY 1.021277 (-1450 2675);
PAINT SKYBLUE (-1450 2675);
DISPLAY INVISIBLE (-1450 2675);
FORCEPROP 1 LAST BODY_TYPE PLUMBING
J 0
(-1695 2482);
DISPLAY 0.340426 (-1695 2482);
PAINT GREEN (-1695 2482);
DISPLAY INVISIBLE (-1695 2482);
FORCEPROP 1 LAST HDL_POWER P3V3_STBY
J 0
(-1950 2400);
DISPLAY 0.872340 (-1950 2400);
PAINT ORANGE (-1950 2400);
DISPLAY INVISIBLE (-1950 2400);
FORCEADD RES..2
(-1650 2350);
FORCEPROP 2 LAST CDS_LIB mstr_discrete
J 0
(-1650 2350);
PAINT ORANGE (-1650 2350);
DISPLAY INVISIBLE (-1650 2350);
FORCEPROP 2 LAST CDS_LOCATION R1D22
J 0
(-1605 2475);
DISPLAY 0.617021 (-1605 2475);
PAINT AQUA (-1605 2475);
DISPLAY INVISIBLE (-1605 2475);
FORCEPROP 2 LAST ROOM HOT_SWAP
J 0
(-1600 2525);
PAINT MONO (-1600 2525);
DISPLAY INVISIBLE (-1600 2525);
FORCEPROP 1 LAST PATH I158
J 0
(-1600 2525);
DISPLAY 0.978723 (-1600 2525);
PAINT WHITE (-1600 2525);
DISPLAY INVISIBLE (-1600 2525);
FORCEPROP 2 LAST SEC 1
J 0
(-1600 2575);
DISPLAY 0.680851 (-1600 2575);
PAINT MONO (-1600 2575);
DISPLAY INVISIBLE (-1600 2575);
FORCEPROP 2 LAST SEC_TYPE 0402
J 0
(-1600 2575);
DISPLAY 1.021277 (-1600 2575);
PAINT ORANGE (-1600 2575);
DISPLAY INVISIBLE (-1600 2575);
FORCEPROP 1 LAST VALUE 10.0K
J 0
(-1605 2425);
DISPLAY 0.617021 (-1605 2425);
PAINT SKYBLUE (-1605 2425);
FORCEPROP 1 LAST TOLERANCE 1%
J 0
(-1605 2375);
DISPLAY 0.617021 (-1605 2375);
PAINT SKYBLUE (-1605 2375);
FORCEPROP 1 LASTPIN (-1650 2450) $PN 1
J 0
(-1645 2412);
DISPLAY 0.617021 (-1645 2412);
PAINT ORANGE (-1645 2412);
FORCEPROP 1 LAST MATERIAL CHIP
J 0
(-1610 2275);
DISPLAY 0.617021 (-1610 2275);
PAINT SKYBLUE (-1610 2275);
FORCEPROP 1 LAST WATTAGE 1/16W
J 0
(-1610 2325);
DISPLAY 0.617021 (-1610 2325);
PAINT SKYBLUE (-1610 2325);
FORCEPROP 1 LASTPIN (-1650 2250) $PN 2
J 0
(-1645 2260);
DISPLAY 0.617021 (-1645 2260);
PAINT ORANGE (-1645 2260);
FORCEPROP 1 LAST LOCATION R1D22
J 0
(-1605 2475);
DISPLAY 0.617021 (-1605 2475);
PAINT AQUA (-1605 2475);
FORCEPROP 1 LAST PART_NUMBER G21796-016
J 0
(-1610 2225);
DISPLAY 0.617021 (-1610 2225);
PAINT BLUE (-1610 2225);
FORCEPROP 1 LAST PACK_TYPE 0402
J 0
(-1610 2175);
DISPLAY 0.617021 (-1610 2175);
PAINT SKYBLUE (-1610 2175);
FORCEADD TPS3700..1
(-350 350);
FORCEPROP 1 LAST PATH I163
J 0
(-350 600);
PAINT GREEN (-350 600);
DISPLAY INVISIBLE (-350 600);
FORCEPROP 1 LAST CDS_LMAN_SYM_OUTLINE -250,200,250,-200
J 0
(-350 350);
DISPLAY 0.468085 (-350 350);
PAINT GREEN (-350 350);
DISPLAY INVISIBLE (-350 350);
FORCEPROP 2 LAST CDS_LIB mstr_vreg
J 0
(-350 350);
PAINT MONO (-350 350);
DISPLAY INVISIBLE (-350 350);
FORCEPROP 1 LAST PACK_TYPE SM
J 0
(-600 700);
PAINT SKYBLUE (-600 700);
DISPLAY INVISIBLE (-600 700);
FORCEPROP 2 LAST SEC_TYPE SM
J 0
(-600 700);
DISPLAY 1.021277 (-600 700);
PAINT ORANGE (-600 700);
DISPLAY INVISIBLE (-600 700);
FORCEPROP 2 LAST SEC 1
J 0
(-600 700);
DISPLAY 0.680851 (-600 700);
PAINT MONO (-600 700);
DISPLAY INVISIBLE (-600 700);
FORCEPROP 2 LAST CDS_LOCATION U9P1
J 0
(-600 650);
DISPLAY 0.617021 (-600 650);
PAINT AQUA (-600 650);
DISPLAY INVISIBLE (-600 650);
FORCEPROP 2 LASTPIN (-650 300) $PN 4
J 2
(-660 310);
DISPLAY 0.617021 (-660 310);
PAINT ORANGE (-660 310);
FORCEPROP 2 LASTPIN (-50 350) $PN 1
J 0
(-40 360);
DISPLAY 0.617021 (-40 360);
PAINT ORANGE (-40 360);
FORCEPROP 2 LASTPIN (-50 450) $PN 6
J 0
(-40 460);
DISPLAY 0.617021 (-40 460);
PAINT ORANGE (-40 460);
FORCEPROP 2 LASTPIN (-50 200) $PN 5
J 0
(-40 210);
DISPLAY 0.617021 (-40 210);
PAINT ORANGE (-40 210);
FORCEPROP 1 LAST MATERIAL IC
J 0
(-600 600);
DISPLAY 0.617021 (-600 600);
PAINT SKYBLUE (-600 600);
FORCEPROP 1 LAST PART_NUMBER H69492-001
J 0
(-600 100);
DISPLAY 0.617021 (-600 100);
PAINT BLUE (-600 100);
FORCEPROP 2 LASTPIN (-650 200) $PN 3
J 2
(-660 210);
DISPLAY 0.617021 (-660 210);
PAINT ORANGE (-660 210);
FORCEPROP 2 LASTPIN (-650 450) $PN 2
J 2
(-660 460);
DISPLAY 0.617021 (-660 460);
PAINT ORANGE (-660 460);
FORCEPROP 1 LAST LOCATION U9P1
J 0
(-600 650);
DISPLAY 0.617021 (-600 650);
PAINT AQUA (-600 650);
FORCEADD TPS3700..1
(-3100 3125);
FORCEPROP 1 LAST CDS_LMAN_SYM_OUTLINE -250,200,250,-200
J 0
(-3100 3125);
DISPLAY 0.468085 (-3100 3125);
PAINT GREEN (-3100 3125);
DISPLAY INVISIBLE (-3100 3125);
FORCEPROP 2 LAST CDS_LIB mstr_vreg
J 0
(-3100 3125);
PAINT MONO (-3100 3125);
DISPLAY INVISIBLE (-3100 3125);
FORCEPROP 1 LAST PATH I170
J 0
(-3100 3375);
PAINT GREEN (-3100 3375);
DISPLAY INVISIBLE (-3100 3375);
FORCEPROP 1 LAST PACK_TYPE SM
J 0
(-3350 3475);
PAINT SKYBLUE (-3350 3475);
DISPLAY INVISIBLE (-3350 3475);
FORCEPROP 2 LAST SEC_TYPE SM
J 0
(-3350 3475);
DISPLAY 1.021277 (-3350 3475);
PAINT ORANGE (-3350 3475);
DISPLAY INVISIBLE (-3350 3475);
FORCEPROP 2 LAST SEC 1
J 0
(-3350 3475);
DISPLAY 0.680851 (-3350 3475);
PAINT MONO (-3350 3475);
DISPLAY INVISIBLE (-3350 3475);
FORCEPROP 2 LAST CDS_LOCATION U1D2
J 0
(-3350 3425);
DISPLAY 0.617021 (-3350 3425);
PAINT AQUA (-3350 3425);
DISPLAY INVISIBLE (-3350 3425);
FORCEPROP 2 LASTPIN (-2800 3225) $PN 6
J 0
(-2790 3235);
DISPLAY 0.617021 (-2790 3235);
PAINT ORANGE (-2790 3235);
FORCEPROP 2 LASTPIN (-2800 3125) $PN 1
J 0
(-2790 3135);
DISPLAY 0.617021 (-2790 3135);
PAINT ORANGE (-2790 3135);
FORCEPROP 2 LASTPIN (-2800 2975) $PN 5
J 0
(-2790 2985);
DISPLAY 0.617021 (-2790 2985);
PAINT ORANGE (-2790 2985);
FORCEPROP 1 LAST PART_NUMBER H69492-001
J 0
(-3350 2875);
DISPLAY 0.617021 (-3350 2875);
PAINT BLUE (-3350 2875);
FORCEPROP 1 LAST LOCATION U1D2
J 0
(-3350 3425);
DISPLAY 0.617021 (-3350 3425);
PAINT AQUA (-3350 3425);
FORCEPROP 1 LAST MATERIAL IC
J 0
(-3350 3375);
DISPLAY 0.617021 (-3350 3375);
PAINT SKYBLUE (-3350 3375);
FORCEPROP 2 LASTPIN (-3400 3075) $PN 4
J 2
(-3410 3085);
DISPLAY 0.617021 (-3410 3085);
PAINT ORANGE (-3410 3085);
FORCEPROP 2 LASTPIN (-3400 2975) $PN 3
J 2
(-3410 2985);
DISPLAY 0.617021 (-3410 2985);
PAINT ORANGE (-3410 2985);
FORCEPROP 2 LASTPIN (-3400 3225) $PN 2
J 2
(-3410 3235);
DISPLAY 0.617021 (-3410 3235);
PAINT ORANGE (-3410 3235);
FORCEADD RES..2
(-4150 2825);
FORCEPROP 2 LAST SEC_TYPE 0402
J 0
(-4100 3050);
DISPLAY 1.021277 (-4100 3050);
PAINT ORANGE (-4100 3050);
DISPLAY INVISIBLE (-4100 3050);
FORCEPROP 2 LAST SEC 1
J 0
(-4100 3050);
DISPLAY 0.680851 (-4100 3050);
PAINT MONO (-4100 3050);
DISPLAY INVISIBLE (-4100 3050);
FORCEPROP 2 LAST CDS_LIB mstr_discrete
J 0
(-4150 2825);
PAINT MONO (-4150 2825);
DISPLAY INVISIBLE (-4150 2825);
FORCEPROP 2 LAST CDS_LOCATION R1D20
J 0
(-4105 2950);
DISPLAY 0.617021 (-4105 2950);
PAINT AQUA (-4105 2950);
DISPLAY INVISIBLE (-4105 2950);
FORCEPROP 1 LAST PATH I172
J 0
(-4100 3000);
DISPLAY 0.978723 (-4100 3000);
PAINT WHITE (-4100 3000);
DISPLAY INVISIBLE (-4100 3000);
FORCEPROP 1 LAST LOCATION R1D20
J 0
(-4105 2950);
DISPLAY 0.617021 (-4105 2950);
PAINT AQUA (-4105 2950);
FORCEPROP 1 LAST PART_NUMBER G21796-109
J 0
(-4110 2700);
DISPLAY 0.617021 (-4110 2700);
PAINT BLUE (-4110 2700);
FORCEPROP 1 LAST VALUE 150.0K
J 0
(-4105 2900);
DISPLAY 0.617021 (-4105 2900);
PAINT SKYBLUE (-4105 2900);
FORCEPROP 1 LAST TOLERANCE 1%
J 0
(-4105 2850);
DISPLAY 0.617021 (-4105 2850);
PAINT SKYBLUE (-4105 2850);
FORCEPROP 1 LAST PACK_TYPE 0402
J 0
(-4110 2650);
DISPLAY 0.617021 (-4110 2650);
PAINT SKYBLUE (-4110 2650);
FORCEPROP 1 LAST MATERIAL CHIP
J 0
(-4110 2750);
DISPLAY 0.617021 (-4110 2750);
PAINT SKYBLUE (-4110 2750);
FORCEPROP 1 LAST WATTAGE 1/16W
J 0
(-4110 2800);
DISPLAY 0.617021 (-4110 2800);
PAINT SKYBLUE (-4110 2800);
FORCEPROP 1 LASTPIN (-4150 2925) $PN 1
J 0
(-4145 2887);
DISPLAY 0.617021 (-4145 2887);
PAINT ORANGE (-4145 2887);
FORCEPROP 1 LASTPIN (-4150 2725) $PN 2
J 0
(-4145 2735);
DISPLAY 0.617021 (-4145 2735);
PAINT ORANGE (-4145 2735);
FORCEADD RES..2
(-4575 3400);
FORCEPROP 2 LAST SEC_TYPE 0402
J 0
(-4525 3625);
DISPLAY 1.021277 (-4525 3625);
PAINT ORANGE (-4525 3625);
DISPLAY INVISIBLE (-4525 3625);
FORCEPROP 2 LAST SEC 1
J 0
(-4525 3625);
DISPLAY 0.680851 (-4525 3625);
PAINT MONO (-4525 3625);
DISPLAY INVISIBLE (-4525 3625);
FORCEPROP 1 LAST PATH I173
J 0
(-4525 3575);
DISPLAY 0.978723 (-4525 3575);
PAINT WHITE (-4525 3575);
DISPLAY INVISIBLE (-4525 3575);
FORCEPROP 2 LAST CDS_LOCATION R1D14
J 0
(-4530 3525);
DISPLAY 0.617021 (-4530 3525);
PAINT AQUA (-4530 3525);
DISPLAY INVISIBLE (-4530 3525);
FORCEPROP 2 LAST CDS_LIB mstr_discrete
J 0
(-4575 3400);
PAINT MONO (-4575 3400);
DISPLAY INVISIBLE (-4575 3400);
FORCEPROP 1 LAST PART_NUMBER G21796-099
J 0
(-4535 3275);
DISPLAY 0.617021 (-4535 3275);
PAINT BLUE (-4535 3275);
FORCEPROP 1 LAST WATTAGE 1/16W
J 0
(-4535 3375);
DISPLAY 0.617021 (-4535 3375);
PAINT SKYBLUE (-4535 3375);
FORCEPROP 1 LAST LOCATION R1D14
J 0
(-4530 3525);
DISPLAY 0.617021 (-4530 3525);
PAINT AQUA (-4530 3525);
FORCEPROP 1 LAST TOLERANCE 1%
J 0
(-4530 3425);
DISPLAY 0.617021 (-4530 3425);
PAINT SKYBLUE (-4530 3425);
FORCEPROP 1 LASTPIN (-4575 3500) $PN 1
J 0
(-4570 3462);
DISPLAY 0.617021 (-4570 3462);
PAINT ORANGE (-4570 3462);
FORCEPROP 1 LAST MATERIAL CHIP
J 0
(-4535 3325);
DISPLAY 0.617021 (-4535 3325);
PAINT SKYBLUE (-4535 3325);
FORCEPROP 1 LASTPIN (-4575 3300) $PN 2
J 0
(-4570 3310);
DISPLAY 0.617021 (-4570 3310);
PAINT ORANGE (-4570 3310);
FORCEPROP 1 LAST PACK_TYPE 0402
J 0
(-4535 3225);
DISPLAY 0.617021 (-4535 3225);
PAINT SKYBLUE (-4535 3225);
FORCEPROP 1 LAST VALUE 105.0K
J 0
(-4530 3475);
DISPLAY 0.617021 (-4530 3475);
PAINT SKYBLUE (-4530 3475);
FORCEADD RES..2
(-4575 2800);
FORCEPROP 2 LAST ROOM HOT_SWAP
J 0
(-4525 2975);
PAINT MONO (-4525 2975);
DISPLAY INVISIBLE (-4525 2975);
FORCEPROP 1 LAST PATH I174
J 0
(-4525 2975);
DISPLAY 0.978723 (-4525 2975);
PAINT WHITE (-4525 2975);
DISPLAY INVISIBLE (-4525 2975);
FORCEPROP 2 LAST CDS_LOCATION R1D12
J 0
(-4530 2925);
DISPLAY 0.617021 (-4530 2925);
PAINT AQUA (-4530 2925);
DISPLAY INVISIBLE (-4530 2925);
FORCEPROP 2 LAST SEC 1
J 0
(-4525 3025);
DISPLAY 0.680851 (-4525 3025);
PAINT MONO (-4525 3025);
DISPLAY INVISIBLE (-4525 3025);
FORCEPROP 2 LAST SEC_TYPE 0402
J 0
(-4525 3025);
DISPLAY 1.021277 (-4525 3025);
PAINT ORANGE (-4525 3025);
DISPLAY INVISIBLE (-4525 3025);
FORCEPROP 2 LAST CDS_LIB mstr_discrete
J 0
(-4575 2800);
PAINT MONO (-4575 2800);
DISPLAY INVISIBLE (-4575 2800);
FORCEPROP 1 LAST PART_NUMBER G21796-016
J 0
(-4535 2675);
DISPLAY 0.617021 (-4535 2675);
PAINT BLUE (-4535 2675);
FORCEPROP 1 LAST TOLERANCE 1%
J 0
(-4530 2825);
DISPLAY 0.617021 (-4530 2825);
PAINT SKYBLUE (-4530 2825);
FORCEPROP 1 LAST VALUE 10.0K
J 0
(-4530 2875);
DISPLAY 0.617021 (-4530 2875);
PAINT SKYBLUE (-4530 2875);
FORCEPROP 1 LAST LOCATION R1D12
J 0
(-4530 2925);
DISPLAY 0.617021 (-4530 2925);
PAINT AQUA (-4530 2925);
FORCEPROP 1 LASTPIN (-4575 2900) $PN 1
J 0
(-4570 2862);
DISPLAY 0.617021 (-4570 2862);
PAINT ORANGE (-4570 2862);
FORCEPROP 1 LASTPIN (-4575 2700) $PN 2
J 0
(-4570 2710);
DISPLAY 0.617021 (-4570 2710);
PAINT ORANGE (-4570 2710);
FORCEPROP 1 LAST WATTAGE 1/16W
J 0
(-4535 2775);
DISPLAY 0.617021 (-4535 2775);
PAINT SKYBLUE (-4535 2775);
FORCEPROP 1 LAST PACK_TYPE 0402
J 0
(-4535 2625);
DISPLAY 0.617021 (-4535 2625);
PAINT SKYBLUE (-4535 2625);
FORCEPROP 1 LAST MATERIAL CHIP
J 0
(-4535 2725);
DISPLAY 0.617021 (-4535 2725);
PAINT SKYBLUE (-4535 2725);
FORCEADD RES..2
(-4150 2450);
FORCEPROP 2 LAST SEC_TYPE 0402
J 0
(-4100 2675);
DISPLAY 1.021277 (-4100 2675);
PAINT ORANGE (-4100 2675);
DISPLAY INVISIBLE (-4100 2675);
FORCEPROP 2 LAST SEC 1
J 0
(-4100 2675);
DISPLAY 0.680851 (-4100 2675);
PAINT MONO (-4100 2675);
DISPLAY INVISIBLE (-4100 2675);
FORCEPROP 2 LAST CDS_LOCATION R1D19
J 0
(-4105 2575);
DISPLAY 0.617021 (-4105 2575);
PAINT AQUA (-4105 2575);
DISPLAY INVISIBLE (-4105 2575);
FORCEPROP 2 LAST ROOM HOT_SWAP
J 0
(-4100 2625);
PAINT MONO (-4100 2625);
DISPLAY INVISIBLE (-4100 2625);
FORCEPROP 1 LAST PATH I175
J 0
(-4100 2625);
DISPLAY 0.978723 (-4100 2625);
PAINT WHITE (-4100 2625);
DISPLAY INVISIBLE (-4100 2625);
FORCEPROP 2 LAST CDS_LIB mstr_discrete
J 0
(-4150 2450);
PAINT MONO (-4150 2450);
DISPLAY INVISIBLE (-4150 2450);
FORCEPROP 1 LAST LOCATION R1D19
J 0
(-4105 2575);
DISPLAY 0.617021 (-4105 2575);
PAINT AQUA (-4105 2575);
FORCEPROP 1 LAST PART_NUMBER G21796-016
J 0
(-4110 2325);
DISPLAY 0.617021 (-4110 2325);
PAINT BLUE (-4110 2325);
FORCEPROP 1 LAST VALUE 10.0K
J 0
(-4105 2525);
DISPLAY 0.617021 (-4105 2525);
PAINT SKYBLUE (-4105 2525);
FORCEPROP 1 LAST TOLERANCE 1%
J 0
(-4105 2475);
DISPLAY 0.617021 (-4105 2475);
PAINT SKYBLUE (-4105 2475);
FORCEPROP 1 LAST PACK_TYPE 0402
J 0
(-4110 2275);
DISPLAY 0.617021 (-4110 2275);
PAINT SKYBLUE (-4110 2275);
FORCEPROP 1 LAST MATERIAL CHIP
J 0
(-4110 2375);
DISPLAY 0.617021 (-4110 2375);
PAINT SKYBLUE (-4110 2375);
FORCEPROP 1 LAST WATTAGE 1/16W
J 0
(-4110 2425);
DISPLAY 0.617021 (-4110 2425);
PAINT SKYBLUE (-4110 2425);
FORCEPROP 1 LASTPIN (-4150 2550) $PN 1
J 0
(-4145 2512);
DISPLAY 0.617021 (-4145 2512);
PAINT ORANGE (-4145 2512);
FORCEPROP 1 LASTPIN (-4150 2350) $PN 2
J 0
(-4145 2360);
DISPLAY 0.617021 (-4145 2360);
PAINT ORANGE (-4145 2360);
FORCEADD GND..1
(-50 50);
FORCEPROP 3 LASTPIN (-50 100) SIG_NAME GND\g
J 0
(-40 110);
DISPLAY 0.659574 (-40 110);
PAINT MONO (-40 110);
DISPLAY INVISIBLE (-40 110);
FORCEPROP 1 LAST PATH I178
J 0
(25 50);
DISPLAY 0.872340 (25 50);
PAINT AQUA (25 50);
DISPLAY INVISIBLE (25 50);
FORCEPROP 1 LAST SIZE 1B
J 0
(25 0);
DISPLAY 0.872340 (25 0);
PAINT AQUA (25 0);
DISPLAY INVISIBLE (25 0);
FORCEPROP 2 LAST CDS_LIB mstr_symbols
J 0
(-50 50);
PAINT MONO (-50 50);
DISPLAY INVISIBLE (-50 50);
FORCEPROP 1 LAST VOLTAGE 0.0V
J 0
(-95 7);
DISPLAY 0.340426 (-95 7);
PAINT SKYBLUE (-95 7);
DISPLAY INVISIBLE (-95 7);
FORCEPROP 1 LAST BODY_TYPE PLUMBING
J 0
(-95 7);
DISPLAY 0.340426 (-95 7);
PAINT GREEN (-95 7);
DISPLAY INVISIBLE (-95 7);
FORCEPROP 1 LAST HDL_POWER GND
J 0
(-50 200);
DISPLAY 0.872340 (-50 200);
PAINT GREEN (-50 200);
DISPLAY INVISIBLE (-50 200);
FORCEADD GND..1
(550 -400);
FORCEPROP 3 LASTPIN (550 -350) SIG_NAME GND\g
J 0
(560 -340);
DISPLAY 0.659574 (560 -340);
PAINT MONO (560 -340);
DISPLAY INVISIBLE (560 -340);
FORCEPROP 2 LAST CDS_LIB mstr_symbols
J 0
(550 -400);
PAINT MONO (550 -400);
DISPLAY INVISIBLE (550 -400);
FORCEPROP 1 LAST SIZE 1B
J 0
(625 -450);
DISPLAY 0.872340 (625 -450);
PAINT AQUA (625 -450);
DISPLAY INVISIBLE (625 -450);
FORCEPROP 1 LAST PATH I179
J 0
(625 -400);
DISPLAY 0.872340 (625 -400);
PAINT AQUA (625 -400);
DISPLAY INVISIBLE (625 -400);
FORCEPROP 1 LAST VOLTAGE 0.0V
J 0
(505 -443);
DISPLAY 0.340426 (505 -443);
PAINT SKYBLUE (505 -443);
DISPLAY INVISIBLE (505 -443);
FORCEPROP 1 LAST BODY_TYPE PLUMBING
J 0
(505 -443);
DISPLAY 0.340426 (505 -443);
PAINT GREEN (505 -443);
DISPLAY INVISIBLE (505 -443);
FORCEPROP 1 LAST HDL_POWER GND
J 0
(550 -250);
DISPLAY 0.872340 (550 -250);
PAINT GREEN (550 -250);
DISPLAY INVISIBLE (550 -250);
FORCEADD AGND0..1
(-4150 2150);
FORCEPROP 3 LASTPIN (-4150 2200) SIG_NAME AGND_HSC\g
J 0
(-4140 2210);
DISPLAY 0.659574 (-4140 2210);
PAINT MONO (-4140 2210);
DISPLAY INVISIBLE (-4140 2210);
FORCEPROP 1 LAST PATH I180
J 0
(-4075 2150);
DISPLAY 0.872340 (-4075 2150);
PAINT AQUA (-4075 2150);
DISPLAY INVISIBLE (-4075 2150);
FORCEPROP 1 LAST VOLTAGE 0
J 0
(-4150 2150);
PAINT SKYBLUE (-4150 2150);
DISPLAY INVISIBLE (-4150 2150);
FORCEPROP 2 LAST BOM_COST MIO_VRD_MAIN
J 0
(-4125 2125);
PAINT ORANGE (-4125 2125);
DISPLAY INVISIBLE (-4125 2125);
FORCEPROP 2 LAST CDS_LIB mstr_symbols
J 0
(-4150 2150);
PAINT MONO (-4150 2150);
DISPLAY INVISIBLE (-4150 2150);
FORCEPROP 2 LAST ROOM VR_P3V3
J 0
(-4175 2125);
PAINT ORANGE (-4175 2125);
DISPLAY INVISIBLE (-4175 2125);
FORCEPROP 1 LAST BODY_TYPE PLUMBING
J 0
(-4195 2107);
DISPLAY 0.340426 (-4195 2107);
PAINT GREEN (-4195 2107);
DISPLAY INVISIBLE (-4195 2107);
FORCEPROP 1 LAST HDL_POWER AGND_HSC
J 1
(-4150 2100);
DISPLAY 0.617021 (-4150 2100);
PAINT GREEN (-4150 2100);
FORCEADD AGND0..1
(-4575 2500);
FORCEPROP 3 LASTPIN (-4575 2550) SIG_NAME AGND_HSC\g
J 0
(-4565 2560);
DISPLAY 0.659574 (-4565 2560);
PAINT MONO (-4565 2560);
DISPLAY INVISIBLE (-4565 2560);
FORCEPROP 1 LAST VOLTAGE 0
J 0
(-4575 2500);
PAINT SKYBLUE (-4575 2500);
DISPLAY INVISIBLE (-4575 2500);
FORCEPROP 2 LAST BOM_COST MIO_VRD_MAIN
J 0
(-4550 2475);
PAINT ORANGE (-4550 2475);
DISPLAY INVISIBLE (-4550 2475);
FORCEPROP 2 LAST CDS_LIB mstr_symbols
J 0
(-4575 2500);
PAINT MONO (-4575 2500);
DISPLAY INVISIBLE (-4575 2500);
FORCEPROP 1 LAST PATH I181
J 0
(-4500 2500);
DISPLAY 0.872340 (-4500 2500);
PAINT AQUA (-4500 2500);
DISPLAY INVISIBLE (-4500 2500);
FORCEPROP 2 LAST ROOM VR_P3V3
J 0
(-4600 2475);
PAINT ORANGE (-4600 2475);
DISPLAY INVISIBLE (-4600 2475);
FORCEPROP 1 LAST BODY_TYPE PLUMBING
J 0
(-4620 2457);
DISPLAY 0.340426 (-4620 2457);
PAINT GREEN (-4620 2457);
DISPLAY INVISIBLE (-4620 2457);
FORCEPROP 1 LAST HDL_POWER AGND_HSC
J 1
(-4550 2425);
DISPLAY 0.617021 (-4550 2425);
PAINT GREEN (-4550 2425);
FORCEADD GND..1
(-2750 2800);
FORCEPROP 3 LASTPIN (-2750 2850) SIG_NAME GND\g
J 0
(-2740 2860);
DISPLAY 0.659574 (-2740 2860);
PAINT MONO (-2740 2860);
DISPLAY INVISIBLE (-2740 2860);
FORCEPROP 1 LAST PATH I183
J 0
(-2675 2800);
DISPLAY 0.872340 (-2675 2800);
PAINT AQUA (-2675 2800);
DISPLAY INVISIBLE (-2675 2800);
FORCEPROP 2 LAST CDS_LIB mstr_symbols
J 0
(-2750 2800);
PAINT MONO (-2750 2800);
DISPLAY INVISIBLE (-2750 2800);
FORCEPROP 1 LAST SIZE 1B
J 0
(-2675 2750);
DISPLAY 0.872340 (-2675 2750);
PAINT AQUA (-2675 2750);
DISPLAY INVISIBLE (-2675 2750);
FORCEPROP 1 LAST VOLTAGE 0.0V
J 0
(-2795 2757);
DISPLAY 0.340426 (-2795 2757);
PAINT SKYBLUE (-2795 2757);
DISPLAY INVISIBLE (-2795 2757);
FORCEPROP 1 LAST BODY_TYPE PLUMBING
J 0
(-2795 2757);
DISPLAY 0.340426 (-2795 2757);
PAINT GREEN (-2795 2757);
DISPLAY INVISIBLE (-2795 2757);
FORCEPROP 1 LAST HDL_POWER GND
J 0
(-2750 2950);
DISPLAY 0.872340 (-2750 2950);
PAINT GREEN (-2750 2950);
DISPLAY INVISIBLE (-2750 2950);
FORCEADD P12V_STBY..1
(-3800 3700);
FORCEPROP 3 LASTPIN (-3800 3650) SIG_NAME P12V_STBY\g
J 0
(-3790 3660);
DISPLAY 0.659574 (-3790 3660);
PAINT MONO (-3790 3660);
DISPLAY INVISIBLE (-3790 3660);
FORCEPROP 1 LAST SIZE 1B
J 0
(-3755 3722);
DISPLAY 0.340426 (-3755 3722);
PAINT GREEN (-3755 3722);
DISPLAY INVISIBLE (-3755 3722);
FORCEPROP 2 LAST CDS_LIB mstr_symbols
J 0
(-3800 3700);
PAINT MONO (-3800 3700);
DISPLAY INVISIBLE (-3800 3700);
FORCEPROP 1 LAST PATH I184
J 0
(-3755 3702);
DISPLAY 0.340426 (-3755 3702);
PAINT GREEN (-3755 3702);
DISPLAY INVISIBLE (-3755 3702);
FORCEPROP 1 LAST VOLTAGE 12.0V
J 0
(-3845 3657);
DISPLAY 0.340426 (-3845 3657);
PAINT SKYBLUE (-3845 3657);
DISPLAY INVISIBLE (-3845 3657);
FORCEPROP 1 LAST BODY_TYPE PLUMBING
J 0
(-3845 3657);
DISPLAY 0.340426 (-3845 3657);
PAINT GREEN (-3845 3657);
DISPLAY INVISIBLE (-3845 3657);
FORCEPROP 1 LAST HDL_POWER P12V_STBY
J 0
(-4100 3575);
DISPLAY 0.872340 (-4100 3575);
PAINT ORANGE (-4100 3575);
DISPLAY INVISIBLE (-4100 3575);
FORCEADD CAP_A..1
R 2
(-825 775);
FORCEPROP 1 LAST PATH I185
J 2
(-875 925);
DISPLAY 0.978723 (-875 925);
PAINT WHITE (-875 925);
DISPLAY INVISIBLE (-875 925);
FORCEPROP 0 LAST ROOM HOT_SWAP
J 0
(-875 925);
DISPLAY 1.021277 (-875 925);
PAINT ORANGE (-875 925);
DISPLAY INVISIBLE (-875 925);
FORCEPROP 2 LAST CDS_LOCATION C9P6
J 2
(-875 875);
DISPLAY 0.617021 (-875 875);
PAINT AQUA (-875 875);
DISPLAY INVISIBLE (-875 875);
FORCEPROP 2 LAST CDS_LIB dev_discrete
J 0
(-825 775);
PAINT ORANGE (-825 775);
DISPLAY INVISIBLE (-825 775);
FORCEPROP 2 LAST CDS_SEC 1
J 0
(-875 925);
PAINT ORANGE (-875 925);
DISPLAY INVISIBLE (-875 925);
FORCEPROP 2 LAST SEC 1
J 0
(-875 975);
DISPLAY 0.680851 (-875 975);
PAINT MONO (-875 975);
DISPLAY INVISIBLE (-875 975);
FORCEPROP 2 LAST SEC_TYPE 0402V
J 0
(-875 975);
DISPLAY 1.021277 (-875 975);
PAINT ORANGE (-875 975);
DISPLAY INVISIBLE (-875 975);
FORCEPROP 1 LAST TOLERANCE 10%
J 2
(-875 725);
DISPLAY 0.617021 (-875 725);
PAINT SKYBLUE (-875 725);
FORCEPROP 1 LAST VOLTAGE 16V
J 2
(-875 775);
DISPLAY 0.617021 (-875 775);
PAINT SKYBLUE (-875 775);
FORCEPROP 1 LAST PACK_TYPE 0402V
J 2
(-875 575);
DISPLAY 0.617021 (-875 575);
PAINT SKYBLUE (-875 575);
FORCEPROP 1 LAST VALUE 0.1UF
J 2
(-875 825);
DISPLAY 0.617021 (-875 825);
PAINT SKYBLUE (-875 825);
FORCEPROP 1 LASTPIN (-825 675) $PN 2
J 2
(-835 655);
DISPLAY 0.617021 (-835 655);
PAINT ORANGE (-835 655);
FORCEPROP 1 LAST PART_NUMBER A36096-030
J 2
(-875 625);
DISPLAY 0.617021 (-875 625);
PAINT BLUE (-875 625);
FORCEPROP 1 LAST MATERIAL X7R
J 2
(-875 675);
DISPLAY 0.617021 (-875 675);
PAINT SKYBLUE (-875 675);
FORCEPROP 1 LASTPIN (-825 875) $PN 1
J 2
(-835 855);
DISPLAY 0.617021 (-835 855);
PAINT ORANGE (-835 855);
FORCEPROP 1 LAST LOCATION C9P6
J 2
(-875 875);
DISPLAY 0.617021 (-875 875);
PAINT AQUA (-875 875);
FORCEADD AGND0..1
(-825 625);
FORCEPROP 3 LASTPIN (-825 675) SIG_NAME AGND_HSC\g
J 0
(-815 685);
DISPLAY 0.659574 (-815 685);
PAINT MONO (-815 685);
DISPLAY INVISIBLE (-815 685);
FORCEPROP 1 LAST PATH I186
J 0
(-750 625);
DISPLAY 0.872340 (-750 625);
PAINT AQUA (-750 625);
DISPLAY INVISIBLE (-750 625);
FORCEPROP 1 LAST VOLTAGE 0
J 0
(-825 625);
PAINT SKYBLUE (-825 625);
DISPLAY INVISIBLE (-825 625);
FORCEPROP 2 LAST CDS_LIB mstr_symbols
J 0
(-825 625);
PAINT MONO (-825 625);
DISPLAY INVISIBLE (-825 625);
FORCEPROP 2 LAST BOM_COST MIO_VRD_MAIN
J 0
(-800 600);
PAINT ORANGE (-800 600);
DISPLAY INVISIBLE (-800 600);
FORCEPROP 2 LAST ROOM VR_P3V3
J 0
(-850 600);
PAINT ORANGE (-850 600);
DISPLAY INVISIBLE (-850 600);
FORCEPROP 1 LAST BODY_TYPE PLUMBING
J 0
(-870 582);
DISPLAY 0.340426 (-870 582);
PAINT GREEN (-870 582);
DISPLAY INVISIBLE (-870 582);
FORCEPROP 1 LAST HDL_POWER AGND_HSC
J 1
(-825 575);
DISPLAY 0.617021 (-825 575);
PAINT GREEN (-825 575);
FORCEADD CAP_A..1
R 2
(-3800 3425);
FORCEPROP 2 LAST SEC 1
J 0
(-3850 3625);
DISPLAY 0.680851 (-3850 3625);
PAINT MONO (-3850 3625);
DISPLAY INVISIBLE (-3850 3625);
FORCEPROP 2 LAST SEC_TYPE 0402V
J 0
(-3850 3625);
DISPLAY 1.021277 (-3850 3625);
PAINT ORANGE (-3850 3625);
DISPLAY INVISIBLE (-3850 3625);
FORCEPROP 1 LAST PATH I187
J 2
(-3850 3575);
DISPLAY 0.978723 (-3850 3575);
PAINT WHITE (-3850 3575);
DISPLAY INVISIBLE (-3850 3575);
FORCEPROP 0 LAST ROOM HOT_SWAP
J 0
(-3850 3575);
DISPLAY 1.021277 (-3850 3575);
PAINT ORANGE (-3850 3575);
DISPLAY INVISIBLE (-3850 3575);
FORCEPROP 2 LAST CDS_SEC 1
J 0
(-3850 3575);
PAINT ORANGE (-3850 3575);
DISPLAY INVISIBLE (-3850 3575);
FORCEPROP 2 LAST CDS_LIB dev_discrete
J 0
(-3800 3425);
PAINT ORANGE (-3800 3425);
DISPLAY INVISIBLE (-3800 3425);
FORCEPROP 2 LAST CDS_LOCATION C1D9
J 2
(-3850 3525);
DISPLAY 0.617021 (-3850 3525);
PAINT AQUA (-3850 3525);
DISPLAY INVISIBLE (-3850 3525);
FORCEPROP 1 LASTPIN (-3800 3525) $PN 1
J 2
(-3810 3505);
DISPLAY 0.617021 (-3810 3505);
PAINT ORANGE (-3810 3505);
FORCEPROP 1 LASTPIN (-3800 3325) $PN 2
J 2
(-3810 3305);
DISPLAY 0.617021 (-3810 3305);
PAINT ORANGE (-3810 3305);
FORCEPROP 1 LAST LOCATION C1D9
J 2
(-3850 3525);
DISPLAY 0.617021 (-3850 3525);
PAINT AQUA (-3850 3525);
FORCEPROP 1 LAST VALUE 0.1UF
J 2
(-3850 3475);
DISPLAY 0.617021 (-3850 3475);
PAINT SKYBLUE (-3850 3475);
FORCEPROP 1 LAST TOLERANCE 10%
J 2
(-3850 3375);
DISPLAY 0.617021 (-3850 3375);
PAINT SKYBLUE (-3850 3375);
FORCEPROP 1 LAST PACK_TYPE 0402V
J 2
(-3850 3225);
DISPLAY 0.617021 (-3850 3225);
PAINT SKYBLUE (-3850 3225);
FORCEPROP 1 LAST VOLTAGE 16V
J 2
(-3850 3425);
DISPLAY 0.617021 (-3850 3425);
PAINT SKYBLUE (-3850 3425);
FORCEPROP 1 LAST PART_NUMBER A36096-030
J 2
(-3850 3275);
DISPLAY 0.617021 (-3850 3275);
PAINT BLUE (-3850 3275);
FORCEPROP 1 LAST MATERIAL X7R
J 2
(-3850 3325);
DISPLAY 0.617021 (-3850 3325);
PAINT SKYBLUE (-3850 3325);
FORCEADD AGND0..1
(-3800 3175);
FORCEPROP 3 LASTPIN (-3800 3225) SIG_NAME AGND_HSC\g
J 0
(-3790 3235);
DISPLAY 0.659574 (-3790 3235);
PAINT MONO (-3790 3235);
DISPLAY INVISIBLE (-3790 3235);
FORCEPROP 2 LAST CDS_LIB mstr_symbols
J 0
(-3800 3175);
PAINT MONO (-3800 3175);
DISPLAY INVISIBLE (-3800 3175);
FORCEPROP 1 LAST VOLTAGE 0
J 0
(-3800 3175);
PAINT SKYBLUE (-3800 3175);
DISPLAY INVISIBLE (-3800 3175);
FORCEPROP 1 LAST PATH I188
J 0
(-3725 3175);
DISPLAY 0.872340 (-3725 3175);
PAINT AQUA (-3725 3175);
DISPLAY INVISIBLE (-3725 3175);
FORCEPROP 2 LAST ROOM VR_P3V3
J 0
(-3825 3150);
PAINT ORANGE (-3825 3150);
DISPLAY INVISIBLE (-3825 3150);
FORCEPROP 2 LAST BOM_COST MIO_VRD_MAIN
J 0
(-3775 3150);
PAINT ORANGE (-3775 3150);
DISPLAY INVISIBLE (-3775 3150);
FORCEPROP 1 LAST BODY_TYPE PLUMBING
J 0
(-3845 3132);
DISPLAY 0.340426 (-3845 3132);
PAINT GREEN (-3845 3132);
DISPLAY INVISIBLE (-3845 3132);
FORCEPROP 1 LAST HDL_POWER AGND_HSC
J 1
(-3800 3125);
DISPLAY 0.617021 (-3800 3125);
PAINT GREEN (-3800 3125);
FORCEADD RES..2
(-2600 3525);
FORCEPROP 2 LAST CDS_LOCATION R1D10
J 0
(-2555 3650);
DISPLAY 0.617021 (-2555 3650);
PAINT AQUA (-2555 3650);
DISPLAY INVISIBLE (-2555 3650);
FORCEPROP 2 LAST CDS_LIB mstr_discrete
J 0
(-2600 3525);
PAINT MONO (-2600 3525);
DISPLAY INVISIBLE (-2600 3525);
FORCEPROP 2 LAST SEC_TYPE 0402
J 0
(-2550 3750);
DISPLAY 1.021277 (-2550 3750);
PAINT ORANGE (-2550 3750);
DISPLAY INVISIBLE (-2550 3750);
FORCEPROP 2 LAST SEC 1
J 0
(-2550 3750);
DISPLAY 0.680851 (-2550 3750);
PAINT MONO (-2550 3750);
DISPLAY INVISIBLE (-2550 3750);
FORCEPROP 1 LAST PATH I189
J 0
(-2550 3700);
DISPLAY 0.978723 (-2550 3700);
PAINT WHITE (-2550 3700);
DISPLAY INVISIBLE (-2550 3700);
FORCEPROP 2 LAST ROOM HOT_SWAP
J 0
(-2550 3700);
PAINT MONO (-2550 3700);
DISPLAY INVISIBLE (-2550 3700);
FORCEPROP 1 LASTPIN (-2600 3625) $PN 1
J 0
(-2595 3587);
DISPLAY 0.617021 (-2595 3587);
PAINT ORANGE (-2595 3587);
FORCEPROP 1 LASTPIN (-2600 3425) $PN 2
J 0
(-2595 3435);
DISPLAY 0.617021 (-2595 3435);
PAINT ORANGE (-2595 3435);
FORCEPROP 1 LAST LOCATION R1D10
J 0
(-2555 3650);
DISPLAY 0.617021 (-2555 3650);
PAINT AQUA (-2555 3650);
FORCEPROP 1 LAST VALUE 10.0K
J 0
(-2555 3600);
DISPLAY 0.617021 (-2555 3600);
PAINT SKYBLUE (-2555 3600);
FORCEPROP 1 LAST TOLERANCE 1%
J 0
(-2555 3550);
DISPLAY 0.617021 (-2555 3550);
PAINT SKYBLUE (-2555 3550);
FORCEPROP 1 LAST PACK_TYPE 0402
J 0
(-2560 3350);
DISPLAY 0.617021 (-2560 3350);
PAINT SKYBLUE (-2560 3350);
FORCEPROP 1 LAST MATERIAL CHIP
J 0
(-2560 3450);
DISPLAY 0.617021 (-2560 3450);
PAINT SKYBLUE (-2560 3450);
FORCEPROP 1 LAST WATTAGE 1/16W
J 0
(-2560 3500);
DISPLAY 0.617021 (-2560 3500);
PAINT SKYBLUE (-2560 3500);
FORCEPROP 1 LAST PART_NUMBER G21796-016
J 0
(-2560 3400);
DISPLAY 0.617021 (-2560 3400);
PAINT BLUE (-2560 3400);
FORCEADD P3V3_STBY..1
(-2600 3875);
FORCEPROP 3 LASTPIN (-2600 3825) SIG_NAME P3V3_STBY\g
J 0
(-2590 3835);
DISPLAY 0.659574 (-2590 3835);
PAINT MONO (-2590 3835);
DISPLAY INVISIBLE (-2590 3835);
FORCEPROP 1 LAST VOLTAGE +3.3V
J 0
(-2400 4025);
DISPLAY 1.021277 (-2400 4025);
PAINT SKYBLUE (-2400 4025);
DISPLAY INVISIBLE (-2400 4025);
FORCEPROP 1 LAST SIZE 1B
J 0
(-2555 3897);
DISPLAY 0.340426 (-2555 3897);
PAINT GREEN (-2555 3897);
DISPLAY INVISIBLE (-2555 3897);
FORCEPROP 1 LAST PATH I190
J 0
(-2555 3877);
DISPLAY 0.340426 (-2555 3877);
PAINT GREEN (-2555 3877);
DISPLAY INVISIBLE (-2555 3877);
FORCEPROP 2 LAST CDS_LIB mstr_symbols
J 0
(-2600 3875);
PAINT MONO (-2600 3875);
DISPLAY INVISIBLE (-2600 3875);
FORCEPROP 1 LAST BODY_TYPE PLUMBING
J 0
(-2645 3832);
DISPLAY 0.340426 (-2645 3832);
PAINT GREEN (-2645 3832);
DISPLAY INVISIBLE (-2645 3832);
FORCEPROP 1 LAST HDL_POWER P3V3_STBY
J 0
(-2900 3750);
DISPLAY 0.872340 (-2900 3750);
PAINT ORANGE (-2900 3750);
DISPLAY INVISIBLE (-2900 3750);
FORCEADD RES..2
(-2825 3500);
FORCEPROP 2 LAST ROOM HOT_SWAP
J 0
(-2775 3675);
PAINT MONO (-2775 3675);
DISPLAY INVISIBLE (-2775 3675);
FORCEPROP 1 LAST PATH I191
J 0
(-2775 3675);
DISPLAY 0.978723 (-2775 3675);
PAINT WHITE (-2775 3675);
DISPLAY INVISIBLE (-2775 3675);
FORCEPROP 2 LAST CDS_LOCATION R1D23
J 0
(-2780 3625);
DISPLAY 0.617021 (-2780 3625);
PAINT AQUA (-2780 3625);
DISPLAY INVISIBLE (-2780 3625);
FORCEPROP 2 LAST SEC 1
J 0
(-2775 3725);
DISPLAY 0.680851 (-2775 3725);
PAINT MONO (-2775 3725);
DISPLAY INVISIBLE (-2775 3725);
FORCEPROP 2 LAST SEC_TYPE 0402
J 0
(-2775 3725);
DISPLAY 1.021277 (-2775 3725);
PAINT ORANGE (-2775 3725);
DISPLAY INVISIBLE (-2775 3725);
FORCEPROP 2 LAST CDS_LIB mstr_discrete
J 0
(-2825 3500);
PAINT MONO (-2825 3500);
DISPLAY INVISIBLE (-2825 3500);
FORCEPROP 1 LASTPIN (-2825 3600) $PN 1
J 0
(-2820 3562);
DISPLAY 0.617021 (-2820 3562);
PAINT ORANGE (-2820 3562);
FORCEPROP 1 LAST TOLERANCE 1%
J 0
(-2780 3525);
DISPLAY 0.617021 (-2780 3525);
PAINT SKYBLUE (-2780 3525);
FORCEPROP 1 LAST MATERIAL CHIP
J 0
(-2785 3425);
DISPLAY 0.617021 (-2785 3425);
PAINT SKYBLUE (-2785 3425);
FORCEPROP 1 LAST PACK_TYPE 0402
J 0
(-2785 3325);
DISPLAY 0.617021 (-2785 3325);
PAINT SKYBLUE (-2785 3325);
FORCEPROP 1 LASTPIN (-2825 3400) $PN 2
J 0
(-2820 3410);
DISPLAY 0.617021 (-2820 3410);
PAINT ORANGE (-2820 3410);
FORCEPROP 1 LAST PART_NUMBER G21796-016
J 0
(-2785 3375);
DISPLAY 0.617021 (-2785 3375);
PAINT BLUE (-2785 3375);
FORCEPROP 1 LAST WATTAGE 1/16W
J 0
(-2785 3475);
DISPLAY 0.617021 (-2785 3475);
PAINT SKYBLUE (-2785 3475);
FORCEPROP 1 LAST VALUE 10.0K
J 0
(-2780 3575);
DISPLAY 0.617021 (-2780 3575);
PAINT SKYBLUE (-2780 3575);
FORCEPROP 1 LAST LOCATION R1D23
J 0
(-2780 3625);
DISPLAY 0.617021 (-2780 3625);
PAINT AQUA (-2780 3625);
FORCEADD RES..2
(275 1075);
FORCEPROP 2 LAST SEC_TYPE 0402
J 0
(325 1300);
DISPLAY 1.021277 (325 1300);
PAINT ORANGE (325 1300);
DISPLAY INVISIBLE (325 1300);
FORCEPROP 2 LAST SEC 1
J 0
(325 1300);
DISPLAY 0.680851 (325 1300);
PAINT MONO (325 1300);
DISPLAY INVISIBLE (325 1300);
FORCEPROP 2 LAST CDS_LOCATION R9P10
J 0
(320 1200);
DISPLAY 0.617021 (320 1200);
PAINT AQUA (320 1200);
DISPLAY INVISIBLE (320 1200);
FORCEPROP 1 LAST PATH I192
J 0
(325 1250);
DISPLAY 0.978723 (325 1250);
PAINT WHITE (325 1250);
DISPLAY INVISIBLE (325 1250);
FORCEPROP 2 LAST ROOM HOT_SWAP
J 0
(325 1250);
PAINT MONO (325 1250);
DISPLAY INVISIBLE (325 1250);
FORCEPROP 2 LAST CDS_LIB mstr_discrete
J 0
(275 1075);
PAINT MONO (275 1075);
DISPLAY INVISIBLE (275 1075);
FORCEPROP 1 LAST TOLERANCE 1%
J 0
(320 1100);
DISPLAY 0.617021 (320 1100);
PAINT SKYBLUE (320 1100);
FORCEPROP 1 LASTPIN (275 975) $PN 2
J 0
(280 985);
DISPLAY 0.617021 (280 985);
PAINT ORANGE (280 985);
FORCEPROP 1 LASTPIN (275 1175) $PN 1
J 0
(280 1137);
DISPLAY 0.617021 (280 1137);
PAINT ORANGE (280 1137);
FORCEPROP 1 LAST LOCATION R9P10
J 0
(320 1200);
DISPLAY 0.617021 (320 1200);
PAINT AQUA (320 1200);
FORCEPROP 1 LAST VALUE 10.0K
J 0
(320 1150);
DISPLAY 0.617021 (320 1150);
PAINT SKYBLUE (320 1150);
FORCEPROP 1 LAST WATTAGE 1/16W
J 0
(315 1050);
DISPLAY 0.617021 (315 1050);
PAINT SKYBLUE (315 1050);
FORCEPROP 1 LAST MATERIAL CHIP
J 0
(315 1000);
DISPLAY 0.617021 (315 1000);
PAINT SKYBLUE (315 1000);
FORCEPROP 1 LAST PART_NUMBER G21796-016
J 0
(315 950);
DISPLAY 0.617021 (315 950);
PAINT BLUE (315 950);
FORCEPROP 1 LAST PACK_TYPE 0402
J 0
(315 900);
DISPLAY 0.617021 (315 900);
PAINT SKYBLUE (315 900);
FORCEADD P3V3_STBY..1
(275 1400);
FORCEPROP 3 LASTPIN (275 1350) SIG_NAME P3V3_STBY\g
J 0
(285 1360);
DISPLAY 0.659574 (285 1360);
PAINT MONO (285 1360);
DISPLAY INVISIBLE (285 1360);
FORCEPROP 1 LAST VOLTAGE +3.3V
J 0
(475 1550);
DISPLAY 1.021277 (475 1550);
PAINT SKYBLUE (475 1550);
DISPLAY INVISIBLE (475 1550);
FORCEPROP 1 LAST SIZE 1B
J 0
(320 1422);
DISPLAY 0.340426 (320 1422);
PAINT GREEN (320 1422);
DISPLAY INVISIBLE (320 1422);
FORCEPROP 1 LAST PATH I194
J 0
(320 1402);
DISPLAY 0.340426 (320 1402);
PAINT GREEN (320 1402);
DISPLAY INVISIBLE (320 1402);
FORCEPROP 2 LAST CDS_LIB mstr_symbols
J 0
(275 1400);
PAINT MONO (275 1400);
DISPLAY INVISIBLE (275 1400);
FORCEPROP 1 LAST BODY_TYPE PLUMBING
J 0
(230 1357);
DISPLAY 0.340426 (230 1357);
PAINT GREEN (230 1357);
DISPLAY INVISIBLE (230 1357);
FORCEPROP 1 LAST HDL_POWER P3V3_STBY
J 0
(-25 1275);
DISPLAY 0.872340 (-25 1275);
PAINT ORANGE (-25 1275);
DISPLAY INVISIBLE (-25 1275);
FORCEADD FET_N_DUAL..5
(-2150 3325);
FORCEPROP 1 LAST PACK_TYPE SMLF
J 0
(-1950 3175);
DISPLAY 0.978723 (-1950 3175);
PAINT SKYBLUE (-1950 3175);
DISPLAY INVISIBLE (-1950 3175);
FORCEPROP 2 LAST SEC_TYPE SMLF
J 0
(-1950 3425);
DISPLAY 1.021277 (-1950 3425);
PAINT ORANGE (-1950 3425);
DISPLAY INVISIBLE (-1950 3425);
FORCEPROP 2 LAST SEC 1
J 0
(-1950 3425);
DISPLAY 0.680851 (-1950 3425);
PAINT MONO (-1950 3425);
DISPLAY INVISIBLE (-1950 3425);
FORCEPROP 2 LAST CDS_LOCATION Q9P1
J 0
(-1950 3325);
DISPLAY 0.617021 (-1950 3325);
PAINT AQUA (-1950 3325);
DISPLAY INVISIBLE (-1950 3325);
FORCEPROP 1 LAST PATH I196
J 0
(-1950 3375);
DISPLAY 0.978723 (-1950 3375);
PAINT BLUE (-1950 3375);
DISPLAY INVISIBLE (-1950 3375);
FORCEPROP 2 LAST ROOM HOT_SWAP
J 0
(-1950 3425);
PAINT MONO (-1950 3425);
DISPLAY INVISIBLE (-1950 3425);
FORCEPROP 2 LAST CDS_LIB mstr_discrete
J 0
(-2150 3325);
PAINT MONO (-2150 3325);
DISPLAY INVISIBLE (-2150 3325);
FORCEPROP 1 LAST PART_NUMBER D24280-001
J 0
(-1950 3125);
DISPLAY 0.617021 (-1950 3125);
PAINT BLUE (-1950 3125);
FORCEPROP 1 LAST VALUE 2N7002DW
J 0
(-1950 3275);
DISPLAY 0.617021 (-1950 3275);
PAINT SKYBLUE (-1950 3275);
FORCEPROP 1 LAST MATERIAL FET
J 0
(-1950 3225);
DISPLAY 0.617021 (-1950 3225);
PAINT SKYBLUE (-1950 3225);
FORCEPROP 1 LASTPIN (-2150 3525) $PN 6
J 2
(-2097 3490);
DISPLAY 0.617021 (-2097 3490);
PAINT WHITE (-2097 3490);
FORCEPROP 1 LASTPIN (-2150 3125) $PN 1
J 2
(-2092 3125);
DISPLAY 0.617021 (-2092 3125);
PAINT WHITE (-2092 3125);
FORCEPROP 1 LASTPIN (-2350 3225) $PN 2
J 2
(-2347 3240);
DISPLAY 0.617021 (-2347 3240);
PAINT WHITE (-2347 3240);
FORCEPROP 1 LAST LOCATION Q9P1
J 0
(-1950 3325);
DISPLAY 0.617021 (-1950 3325);
PAINT AQUA (-1950 3325);
FORCEADD GND..1
(-2150 3000);
FORCEPROP 3 LASTPIN (-2150 3050) SIG_NAME GND\g
J 0
(-2140 3060);
DISPLAY 0.659574 (-2140 3060);
PAINT MONO (-2140 3060);
DISPLAY INVISIBLE (-2140 3060);
FORCEPROP 1 LAST VOLTAGE 0.0V
J 0
(-2195 2957);
DISPLAY 0.340426 (-2195 2957);
PAINT SKYBLUE (-2195 2957);
DISPLAY INVISIBLE (-2195 2957);
FORCEPROP 1 LAST SIZE 1B
J 0
(-2075 2950);
DISPLAY 0.872340 (-2075 2950);
PAINT AQUA (-2075 2950);
DISPLAY INVISIBLE (-2075 2950);
FORCEPROP 2 LAST CDS_LIB mstr_symbols
J 0
(-2150 3000);
PAINT MONO (-2150 3000);
DISPLAY INVISIBLE (-2150 3000);
FORCEPROP 1 LAST PATH I197
J 0
(-2075 3000);
DISPLAY 0.872340 (-2075 3000);
PAINT AQUA (-2075 3000);
DISPLAY INVISIBLE (-2075 3000);
FORCEPROP 1 LAST BODY_TYPE PLUMBING
J 0
(-2195 2957);
DISPLAY 0.340426 (-2195 2957);
PAINT GREEN (-2195 2957);
DISPLAY INVISIBLE (-2195 2957);
FORCEPROP 1 LAST HDL_POWER GND
J 0
(-2150 3150);
DISPLAY 0.872340 (-2150 3150);
PAINT GREEN (-2150 3150);
DISPLAY INVISIBLE (-2150 3150);
FORCEADD RES..1
(-1900 3850);
FORCEPROP 2 LAST CDS_LIB mstr_discrete
J 0
(-1900 3850);
PAINT MONO (-1900 3850);
DISPLAY INVISIBLE (-1900 3850);
FORCEPROP 1 LAST PATH I198
J 0
(-1950 4000);
DISPLAY 0.978723 (-1950 4000);
PAINT WHITE (-1950 4000);
DISPLAY INVISIBLE (-1950 4000);
FORCEPROP 2 LAST SEC 1
J 0
(-1950 4050);
DISPLAY 0.680851 (-1950 4050);
PAINT MONO (-1950 4050);
DISPLAY INVISIBLE (-1950 4050);
FORCEPROP 2 LAST SEC_TYPE 0402
J 0
(-1950 4050);
DISPLAY 1.021277 (-1950 4050);
PAINT ORANGE (-1950 4050);
DISPLAY INVISIBLE (-1950 4050);
FORCEPROP 2 LAST ROOM HOT_SWAP
J 0
(-1925 3950);
PAINT MONO (-1925 3950);
DISPLAY INVISIBLE (-1925 3950);
FORCEPROP 2 LAST CDS_LOCATION R9P15
J 0
(-2000 3900);
DISPLAY 0.617021 (-2000 3900);
PAINT AQUA (-2000 3900);
DISPLAY INVISIBLE (-2000 3900);
FORCEPROP 1 LAST MATERIAL EMPTY
J 0
(-1925 3775);
DISPLAY 0.617021 (-1925 3775);
PAINT RED (-1925 3775);
FORCEPROP 1 LAST TOLERANCE 5%
J 0
(-1850 3800);
DISPLAY 0.617021 (-1850 3800);
PAINT SKYBLUE (-1850 3800);
FORCEPROP 1 LAST PACK_TYPE 0402
J 0
(-1825 3775);
DISPLAY 0.617021 (-1825 3775);
PAINT SKYBLUE (-1825 3775);
FORCEPROP 1 LASTPIN (-1800 3850) $PN 2
J 0
(-1838 3862);
DISPLAY 0.617021 (-1838 3862);
PAINT ORANGE (-1838 3862);
FORCEPROP 1 LAST LOCATION R9P15
J 0
(-2000 3900);
DISPLAY 0.617021 (-2000 3900);
PAINT AQUA (-2000 3900);
FORCEPROP 1 LASTPIN (-2000 3850) $PN 1
J 0
(-1988 3862);
DISPLAY 0.617021 (-1988 3862);
PAINT ORANGE (-1988 3862);
FORCEPROP 1 LAST PART_NUMBER G21497-005
J 0
(-1925 3900);
DISPLAY 0.617021 (-1925 3900);
PAINT BLUE (-1925 3900);
FORCEPROP 1 LAST VALUE 0.0
J 2
(-1925 3800);
DISPLAY 0.617021 (-1925 3800);
PAINT SKYBLUE (-1925 3800);
FORCEPROP 1 LAST WATTAGE 1/16W
J 2
(-1950 3750);
DISPLAY 0.617021 (-1950 3750);
PAINT SKYBLUE (-1950 3750);
FORCEADD FET_N_DUAL..5
(550 -100);
FORCEPROP 2 LAST SEC_TYPE SMLF
J 0
(750 0);
DISPLAY 1.021277 (750 0);
PAINT ORANGE (750 0);
DISPLAY INVISIBLE (750 0);
FORCEPROP 2 LAST SEC 2
J 0
(750 0);
DISPLAY 0.680851 (750 0);
PAINT MONO (750 0);
DISPLAY INVISIBLE (750 0);
FORCEPROP 2 LAST ROOM HOT_SWAP
J 0
(750 0);
PAINT MONO (750 0);
DISPLAY INVISIBLE (750 0);
FORCEPROP 1 LAST PACK_TYPE SMLF
J 0
(750 -250);
DISPLAY 0.978723 (750 -250);
PAINT SKYBLUE (750 -250);
DISPLAY INVISIBLE (750 -250);
FORCEPROP 2 LAST CDS_LOCATION Q9P1
J 0
(750 -100);
DISPLAY 0.617021 (750 -100);
PAINT AQUA (750 -100);
DISPLAY INVISIBLE (750 -100);
FORCEPROP 1 LAST PATH I199
J 0
(750 -50);
DISPLAY 0.978723 (750 -50);
PAINT BLUE (750 -50);
DISPLAY INVISIBLE (750 -50);
FORCEPROP 2 LAST CDS_LIB mstr_discrete
J 0
(550 -100);
PAINT MONO (550 -100);
DISPLAY INVISIBLE (550 -100);
FORCEPROP 1 LASTPIN (550 100) $PN 3
J 2
(603 65);
DISPLAY 0.617021 (603 65);
PAINT WHITE (603 65);
FORCEPROP 1 LAST PART_NUMBER D24280-001
J 0
(750 -300);
DISPLAY 0.617021 (750 -300);
PAINT BLUE (750 -300);
FORCEPROP 1 LAST LOCATION Q9P1
J 0
(750 -100);
DISPLAY 0.617021 (750 -100);
PAINT AQUA (750 -100);
FORCEPROP 1 LAST VALUE 2N7002DW
J 0
(750 -150);
DISPLAY 0.617021 (750 -150);
PAINT SKYBLUE (750 -150);
FORCEPROP 1 LAST MATERIAL FET
J 0
(750 -200);
DISPLAY 0.617021 (750 -200);
PAINT SKYBLUE (750 -200);
FORCEPROP 1 LASTPIN (550 -300) $PN 4
J 2
(608 -300);
DISPLAY 0.617021 (608 -300);
PAINT WHITE (608 -300);
FORCEPROP 1 LASTPIN (350 -200) $PN 5
J 2
(353 -185);
DISPLAY 0.617021 (353 -185);
PAINT WHITE (353 -185);
FORCEADD TPS3700..1
(-3425 -150);
FORCEPROP 1 LAST PATH I200
J 0
(-3425 100);
PAINT GREEN (-3425 100);
DISPLAY INVISIBLE (-3425 100);
FORCEPROP 1 LAST PACK_TYPE SM
J 0
(-3675 200);
PAINT SKYBLUE (-3675 200);
DISPLAY INVISIBLE (-3675 200);
FORCEPROP 2 LAST CDS_SEC 1
J 0
(-3675 200);
PAINT MONO (-3675 200);
DISPLAY INVISIBLE (-3675 200);
FORCEPROP 2 LAST $SEC 1
J 0
(-3675 200);
PAINT MONO (-3675 200);
DISPLAY INVISIBLE (-3675 200);
FORCEPROP 2 LAST CDS_LOCATION U9P2
J 0
(-3675 150);
DISPLAY 0.617021 (-3675 150);
PAINT AQUA (-3675 150);
DISPLAY INVISIBLE (-3675 150);
FORCEPROP 2 LAST CDS_LIB mstr_vreg
J 0
(-3425 -150);
PAINT MONO (-3425 -150);
DISPLAY INVISIBLE (-3425 -150);
FORCEPROP 1 LAST CDS_LMAN_SYM_OUTLINE -250,200,250,-200
J 0
(-3425 -150);
DISPLAY 0.468085 (-3425 -150);
PAINT GREEN (-3425 -150);
DISPLAY INVISIBLE (-3425 -150);
FORCEPROP 1 LAST MATERIAL IC
J 0
(-3675 100);
DISPLAY 0.617021 (-3675 100);
PAINT SKYBLUE (-3675 100);
FORCEPROP 2 LASTPIN (-3125 -50) $PN 6
J 0
(-3115 -40);
DISPLAY 0.617021 (-3115 -40);
PAINT MONO (-3115 -40);
FORCEPROP 2 LASTPIN (-3125 -150) $PN 1
J 0
(-3115 -140);
DISPLAY 0.617021 (-3115 -140);
PAINT MONO (-3115 -140);
FORCEPROP 2 LASTPIN (-3125 -300) $PN 5
J 0
(-3115 -290);
DISPLAY 0.617021 (-3115 -290);
PAINT MONO (-3115 -290);
FORCEPROP 1 LAST PART_NUMBER H69492-001
J 0
(-3675 -400);
DISPLAY 0.617021 (-3675 -400);
PAINT BLUE (-3675 -400);
FORCEPROP 2 LASTPIN (-3725 -50) $PN 2
J 2
(-3735 -40);
DISPLAY 0.617021 (-3735 -40);
PAINT MONO (-3735 -40);
FORCEPROP 2 LASTPIN (-3725 -300) $PN 3
J 2
(-3735 -290);
DISPLAY 0.617021 (-3735 -290);
PAINT MONO (-3735 -290);
FORCEPROP 2 LASTPIN (-3725 -200) $PN 4
J 2
(-3735 -190);
DISPLAY 0.617021 (-3735 -190);
PAINT MONO (-3735 -190);
FORCEPROP 1 LAST LOCATION U9P2
J 0
(-3675 150);
DISPLAY 0.617021 (-3675 150);
PAINT AQUA (-3675 150);
FORCEADD CAP_A..1
R 2
(-3450 500);
FORCEPROP 2 LAST SEC 1
J 0
(-3500 700);
DISPLAY 0.680851 (-3500 700);
PAINT MONO (-3500 700);
DISPLAY INVISIBLE (-3500 700);
FORCEPROP 2 LAST SEC_TYPE 0402V
J 0
(-3500 700);
DISPLAY 1.021277 (-3500 700);
PAINT ORANGE (-3500 700);
DISPLAY INVISIBLE (-3500 700);
FORCEPROP 2 LAST CDS_SEC 1
J 0
(-3500 650);
PAINT ORANGE (-3500 650);
DISPLAY INVISIBLE (-3500 650);
FORCEPROP 2 LAST CDS_LOCATION C9P11
J 2
(-3500 600);
DISPLAY 0.617021 (-3500 600);
PAINT AQUA (-3500 600);
DISPLAY INVISIBLE (-3500 600);
FORCEPROP 0 LAST ROOM HOT_SWAP
J 0
(-3500 650);
DISPLAY 1.021277 (-3500 650);
PAINT ORANGE (-3500 650);
DISPLAY INVISIBLE (-3500 650);
FORCEPROP 1 LAST PATH I201
J 2
(-3500 650);
DISPLAY 0.978723 (-3500 650);
PAINT WHITE (-3500 650);
DISPLAY INVISIBLE (-3500 650);
FORCEPROP 2 LAST CDS_LIB dev_discrete
J 0
(-3450 500);
PAINT ORANGE (-3450 500);
DISPLAY INVISIBLE (-3450 500);
FORCEPROP 1 LAST MATERIAL X7R
J 2
(-3500 400);
DISPLAY 0.617021 (-3500 400);
PAINT SKYBLUE (-3500 400);
FORCEPROP 1 LASTPIN (-3450 600) $PN 1
J 2
(-3460 580);
DISPLAY 0.617021 (-3460 580);
PAINT ORANGE (-3460 580);
FORCEPROP 1 LAST TOLERANCE 10%
J 2
(-3500 450);
DISPLAY 0.617021 (-3500 450);
PAINT SKYBLUE (-3500 450);
FORCEPROP 1 LAST PACK_TYPE 0402V
J 2
(-3500 300);
DISPLAY 0.617021 (-3500 300);
PAINT SKYBLUE (-3500 300);
FORCEPROP 1 LAST PART_NUMBER A36096-030
J 2
(-3500 350);
DISPLAY 0.617021 (-3500 350);
PAINT BLUE (-3500 350);
FORCEPROP 1 LAST LOCATION C9P11
J 2
(-3500 600);
DISPLAY 0.617021 (-3500 600);
PAINT AQUA (-3500 600);
FORCEPROP 1 LAST VALUE 0.1UF
J 2
(-3500 550);
DISPLAY 0.617021 (-3500 550);
PAINT SKYBLUE (-3500 550);
FORCEPROP 1 LAST VOLTAGE 16V
J 2
(-3500 500);
DISPLAY 0.617021 (-3500 500);
PAINT SKYBLUE (-3500 500);
FORCEPROP 1 LASTPIN (-3450 400) $PN 2
J 2
(-3460 380);
DISPLAY 0.617021 (-3460 380);
PAINT ORANGE (-3460 380);
FORCEADD GND..1
(-3450 225);
FORCEPROP 3 LASTPIN (-3450 275) SIG_NAME GND\g
J 0
(-3440 285);
DISPLAY 0.659574 (-3440 285);
PAINT MONO (-3440 285);
DISPLAY INVISIBLE (-3440 285);
FORCEPROP 1 LAST PATH I202
J 0
(-3375 225);
DISPLAY 0.872340 (-3375 225);
PAINT AQUA (-3375 225);
DISPLAY INVISIBLE (-3375 225);
FORCEPROP 2 LAST CDS_LIB mstr_symbols
J 0
(-3450 225);
PAINT MONO (-3450 225);
DISPLAY INVISIBLE (-3450 225);
FORCEPROP 1 LAST SIZE 1B
J 0
(-3375 175);
DISPLAY 0.872340 (-3375 175);
PAINT AQUA (-3375 175);
DISPLAY INVISIBLE (-3375 175);
FORCEPROP 1 LAST VOLTAGE 0.0V
J 0
(-3495 182);
DISPLAY 0.340426 (-3495 182);
PAINT SKYBLUE (-3495 182);
DISPLAY INVISIBLE (-3495 182);
FORCEPROP 1 LAST BODY_TYPE PLUMBING
J 0
(-3495 182);
DISPLAY 0.340426 (-3495 182);
PAINT GREEN (-3495 182);
DISPLAY INVISIBLE (-3495 182);
FORCEPROP 1 LAST HDL_POWER GND
J 0
(-3450 375);
DISPLAY 0.872340 (-3450 375);
PAINT GREEN (-3450 375);
DISPLAY INVISIBLE (-3450 375);
FORCEADD FET_N..8
(-3500 1300);
FORCEPROP 2 LAST CDS_LIB mstr_discrete
J 0
(-3500 1300);
PAINT ORANGE (-3500 1300);
DISPLAY INVISIBLE (-3500 1300);
FORCEPROP 2 LAST CDS_LOCATION Q1D2
J 0
(-3300 1300);
DISPLAY 0.617021 (-3300 1300);
PAINT AQUA (-3300 1300);
DISPLAY INVISIBLE (-3300 1300);
FORCEPROP 2 LAST SEC 1
J 0
(-3300 1400);
DISPLAY 0.680851 (-3300 1400);
PAINT MONO (-3300 1400);
DISPLAY INVISIBLE (-3300 1400);
FORCEPROP 2 LAST SEC_TYPE SOT23LF
J 0
(-3300 1400);
DISPLAY 1.021277 (-3300 1400);
PAINT ORANGE (-3300 1400);
DISPLAY INVISIBLE (-3300 1400);
FORCEPROP 1 LAST PATH I203
J 0
(-3300 1350);
DISPLAY 0.978723 (-3300 1350);
PAINT BLUE (-3300 1350);
DISPLAY INVISIBLE (-3300 1350);
FORCEPROP 0 LAST ROOM HOT_SWAP
J 0
(-3300 1400);
DISPLAY 1.021277 (-3300 1400);
PAINT ORANGE (-3300 1400);
DISPLAY INVISIBLE (-3300 1400);
FORCEPROP 1 LAST PACK_TYPE SOT23LF
J 0
(-3300 1150);
DISPLAY 0.978723 (-3300 1150);
PAINT SKYBLUE (-3300 1150);
DISPLAY INVISIBLE (-3300 1150);
FORCEPROP 1 LASTPIN (-3700 1200) $PN 1
J 2
(-3697 1215);
DISPLAY 0.617021 (-3697 1215);
PAINT WHITE (-3697 1215);
FORCEPROP 1 LASTPIN (-3500 1500) $PN 3
J 2
(-3447 1465);
DISPLAY 0.617021 (-3447 1465);
PAINT WHITE (-3447 1465);
FORCEPROP 1 LAST LOCATION Q1D2
J 0
(-3300 1300);
DISPLAY 0.617021 (-3300 1300);
PAINT AQUA (-3300 1300);
FORCEPROP 1 LAST VALUE 2N7002
J 0
(-3300 1250);
DISPLAY 0.617021 (-3300 1250);
PAINT SKYBLUE (-3300 1250);
FORCEPROP 1 LASTPIN (-3500 1100) $PN 2
J 2
(-3442 1100);
DISPLAY 0.617021 (-3442 1100);
PAINT WHITE (-3442 1100);
FORCEPROP 1 LAST MATERIAL FET
J 0
(-3300 1200);
DISPLAY 0.617021 (-3300 1200);
PAINT SKYBLUE (-3300 1200);
FORCEPROP 1 LAST PART_NUMBER C79254-001
J 0
(-3300 1100);
DISPLAY 0.617021 (-3300 1100);
PAINT BLUE (-3300 1100);
FORCEADD RES..2
(-3500 1750);
FORCEPROP 0 LAST ROOM HOT_SWAP
J 0
(-3450 1975);
DISPLAY 1.021277 (-3450 1975);
PAINT ORANGE (-3450 1975);
DISPLAY INVISIBLE (-3450 1975);
FORCEPROP 1 LAST PATH I204
J 0
(-3450 1925);
DISPLAY 0.978723 (-3450 1925);
PAINT WHITE (-3450 1925);
DISPLAY INVISIBLE (-3450 1925);
FORCEPROP 2 LAST SEC 1
J 0
(-3450 1975);
DISPLAY 0.680851 (-3450 1975);
PAINT MONO (-3450 1975);
DISPLAY INVISIBLE (-3450 1975);
FORCEPROP 2 LAST SEC_TYPE 0402
J 0
(-3450 1975);
DISPLAY 1.021277 (-3450 1975);
PAINT ORANGE (-3450 1975);
DISPLAY INVISIBLE (-3450 1975);
FORCEPROP 2 LAST CDS_LOCATION R1D21
J 0
(-3455 1875);
DISPLAY 0.617021 (-3455 1875);
PAINT AQUA (-3455 1875);
DISPLAY INVISIBLE (-3455 1875);
FORCEPROP 2 LAST CDS_LIB mstr_discrete
J 0
(-3500 1750);
PAINT ORANGE (-3500 1750);
DISPLAY INVISIBLE (-3500 1750);
FORCEPROP 1 LAST LOCATION R1D21
J 0
(-3455 1875);
DISPLAY 0.617021 (-3455 1875);
PAINT AQUA (-3455 1875);
FORCEPROP 1 LAST VALUE 4.75K
J 0
(-3455 1825);
DISPLAY 0.617021 (-3455 1825);
PAINT SKYBLUE (-3455 1825);
FORCEPROP 1 LASTPIN (-3500 1850) $PN 1
J 0
(-3495 1812);
DISPLAY 0.617021 (-3495 1812);
PAINT ORANGE (-3495 1812);
FORCEPROP 1 LAST TOLERANCE 1%
J 0
(-3455 1775);
DISPLAY 0.617021 (-3455 1775);
PAINT SKYBLUE (-3455 1775);
FORCEPROP 1 LASTPIN (-3500 1650) $PN 2
J 0
(-3495 1660);
DISPLAY 0.617021 (-3495 1660);
PAINT ORANGE (-3495 1660);
FORCEPROP 1 LAST PART_NUMBER G21796-072
J 0
(-3460 1625);
DISPLAY 0.617021 (-3460 1625);
PAINT BLUE (-3460 1625);
FORCEPROP 1 LAST PACK_TYPE 0402
J 0
(-3460 1575);
DISPLAY 0.617021 (-3460 1575);
PAINT SKYBLUE (-3460 1575);
FORCEPROP 1 LAST WATTAGE 1/16W
J 0
(-3460 1725);
DISPLAY 0.617021 (-3460 1725);
PAINT SKYBLUE (-3460 1725);
FORCEPROP 1 LAST MATERIAL CHIP
J 0
(-3460 1675);
DISPLAY 0.617021 (-3460 1675);
PAINT SKYBLUE (-3460 1675);
FORCEADD P3V3_STBY..1
(-3500 1950);
FORCEPROP 3 LASTPIN (-3500 1900) SIG_NAME P3V3_STBY\g
J 0
(-3490 1910);
DISPLAY 0.659574 (-3490 1910);
PAINT MONO (-3490 1910);
DISPLAY INVISIBLE (-3490 1910);
FORCEPROP 1 LAST PATH I205
J 0
(-3455 1952);
DISPLAY 0.340426 (-3455 1952);
PAINT GREEN (-3455 1952);
DISPLAY INVISIBLE (-3455 1952);
FORCEPROP 1 LAST SIZE 1B
J 0
(-3455 1972);
DISPLAY 0.340426 (-3455 1972);
PAINT GREEN (-3455 1972);
DISPLAY INVISIBLE (-3455 1972);
FORCEPROP 2 LAST CDS_LIB mstr_symbols
J 0
(-3500 1950);
PAINT ORANGE (-3500 1950);
DISPLAY INVISIBLE (-3500 1950);
FORCEPROP 1 LAST VOLTAGE 3.3V
J 0
(-3545 1907);
DISPLAY 0.340426 (-3545 1907);
PAINT SKYBLUE (-3545 1907);
DISPLAY INVISIBLE (-3545 1907);
FORCEPROP 1 LAST BODY_TYPE PLUMBING
J 0
(-3545 1907);
DISPLAY 0.340426 (-3545 1907);
PAINT GREEN (-3545 1907);
DISPLAY INVISIBLE (-3545 1907);
FORCEPROP 1 LAST HDL_POWER P3V3_STBY
J 0
(-3800 1825);
DISPLAY 0.872340 (-3800 1825);
PAINT ORANGE (-3800 1825);
DISPLAY INVISIBLE (-3800 1825);
FORCEADD GND..1
(-3500 925);
FORCEPROP 3 LASTPIN (-3500 975) SIG_NAME GND\g
J 0
(-3490 985);
DISPLAY 0.659574 (-3490 985);
PAINT MONO (-3490 985);
DISPLAY INVISIBLE (-3490 985);
FORCEPROP 1 LAST VOLTAGE 0.0V
J 0
(-3545 882);
DISPLAY 0.340426 (-3545 882);
PAINT SKYBLUE (-3545 882);
DISPLAY INVISIBLE (-3545 882);
FORCEPROP 1 LAST SIZE 1B
J 0
(-3425 875);
DISPLAY 0.872340 (-3425 875);
PAINT AQUA (-3425 875);
DISPLAY INVISIBLE (-3425 875);
FORCEPROP 1 LAST PATH I206
J 0
(-3425 925);
DISPLAY 0.872340 (-3425 925);
PAINT AQUA (-3425 925);
DISPLAY INVISIBLE (-3425 925);
FORCEPROP 2 LAST CDS_LIB mstr_symbols
J 0
(-3500 925);
PAINT ORANGE (-3500 925);
DISPLAY INVISIBLE (-3500 925);
FORCEPROP 1 LAST BODY_TYPE PLUMBING
J 0
(-3545 882);
DISPLAY 0.340426 (-3545 882);
PAINT GREEN (-3545 882);
DISPLAY INVISIBLE (-3545 882);
FORCEPROP 1 LAST HDL_POWER GND
J 0
(-3500 1075);
DISPLAY 0.872340 (-3500 1075);
PAINT GREEN (-3500 1075);
DISPLAY INVISIBLE (-3500 1075);
FORCEADD OFFPAGE..1
(-4375 1200);
FORCEPROP 2 LAST CDS_LIB mstr_standard
J 0
(-4375 1200);
PAINT ORANGE (-4375 1200);
DISPLAY INVISIBLE (-4375 1200);
FORCEPROP 2 LAST PATH I207
J 0
(-4325 1275);
DISPLAY 1.021277 (-4325 1275);
PAINT ORANGE (-4325 1275);
DISPLAY INVISIBLE (-4325 1275);
FORCEPROP 1 LAST OFFPAGE TRUE
J 0
(-4050 1075);
DISPLAY 0.872340 (-4050 1075);
PAINT GREEN (-4050 1075);
DISPLAY INVISIBLE (-4050 1075);
FORCEPROP 1 LAST COMMENT_BODY TRUE
J 0
(-4250 1100);
DISPLAY 0.872340 (-4250 1100);
PAINT GREEN (-4250 1100);
DISPLAY INVISIBLE (-4250 1100);
FORCEPROP 2 LAST $XR0 120 
J 0
(-4627 1200);
DISPLAY 0.638298 (-4627 1200);
PAINT MONO (-4627 1200);
FORCEPROP 2 LAST $XR1 126 
J 0
(-4747 1200);
DISPLAY 0.638298 (-4747 1200);
PAINT MONO (-4747 1200);
FORCEPROP 2 LAST $XR2 145 
J 0
(-4867 1200);
DISPLAY 0.638298 (-4867 1200);
PAINT MONO (-4867 1200);
FORCEADD RES..2
(1750 225);
FORCEPROP 2 LAST SEC_TYPE 0402
J 0
(1800 450);
DISPLAY 1.021277 (1800 450);
PAINT ORANGE (1800 450);
DISPLAY INVISIBLE (1800 450);
FORCEPROP 2 LAST SEC 1
J 0
(1800 450);
DISPLAY 0.680851 (1800 450);
PAINT MONO (1800 450);
DISPLAY INVISIBLE (1800 450);
FORCEPROP 2 LAST CDS_LOCATION R9P4
J 0
(1795 350);
DISPLAY 0.617021 (1795 350);
PAINT AQUA (1795 350);
DISPLAY INVISIBLE (1795 350);
FORCEPROP 1 LAST PATH I210
J 0
(1800 400);
DISPLAY 0.978723 (1800 400);
PAINT WHITE (1800 400);
DISPLAY INVISIBLE (1800 400);
FORCEPROP 2 LAST ROOM HOT_SWAP
J 0
(1800 400);
PAINT MONO (1800 400);
DISPLAY INVISIBLE (1800 400);
FORCEPROP 2 LAST CDS_LIB mstr_discrete
J 0
(1750 225);
PAINT MONO (1750 225);
DISPLAY INVISIBLE (1750 225);
FORCEPROP 1 LAST PART_NUMBER G21796-344
J 0
(1790 100);
DISPLAY 0.617021 (1790 100);
PAINT BLUE (1790 100);
FORCEPROP 1 LAST LOCATION R9P4
J 0
(1795 350);
DISPLAY 0.617021 (1795 350);
PAINT AQUA (1795 350);
FORCEPROP 1 LAST VALUE 2.7K
J 0
(1795 300);
DISPLAY 0.617021 (1795 300);
PAINT SKYBLUE (1795 300);
FORCEPROP 1 LAST TOLERANCE 1%
J 0
(1795 250);
DISPLAY 0.617021 (1795 250);
PAINT SKYBLUE (1795 250);
FORCEPROP 1 LAST PACK_TYPE 0402
J 0
(1790 50);
DISPLAY 0.617021 (1790 50);
PAINT SKYBLUE (1790 50);
FORCEPROP 1 LAST MATERIAL CHIP
J 0
(1790 150);
DISPLAY 0.617021 (1790 150);
PAINT SKYBLUE (1790 150);
FORCEPROP 1 LAST WATTAGE 1/16W
J 0
(1790 200);
DISPLAY 0.617021 (1790 200);
PAINT SKYBLUE (1790 200);
FORCEPROP 1 LASTPIN (1750 325) $PN 1
J 0
(1755 287);
DISPLAY 0.617021 (1755 287);
PAINT ORANGE (1755 287);
FORCEPROP 1 LASTPIN (1750 125) $PN 2
J 0
(1755 135);
DISPLAY 0.617021 (1755 135);
PAINT ORANGE (1755 135);
FORCEADD P3V3_STBY..1
(1750 450);
FORCEPROP 3 LASTPIN (1750 400) SIG_NAME P3V3_STBY\g
J 0
(1760 410);
DISPLAY 0.659574 (1760 410);
PAINT MONO (1760 410);
DISPLAY INVISIBLE (1760 410);
FORCEPROP 1 LAST VOLTAGE +3.3V
J 0
(1950 600);
DISPLAY 1.021277 (1950 600);
PAINT SKYBLUE (1950 600);
DISPLAY INVISIBLE (1950 600);
FORCEPROP 1 LAST SIZE 1B
J 0
(1795 472);
DISPLAY 0.340426 (1795 472);
PAINT GREEN (1795 472);
DISPLAY INVISIBLE (1795 472);
FORCEPROP 1 LAST PATH I211
J 0
(1795 452);
DISPLAY 0.340426 (1795 452);
PAINT GREEN (1795 452);
DISPLAY INVISIBLE (1795 452);
FORCEPROP 2 LAST CDS_LIB mstr_symbols
J 0
(1750 450);
PAINT ORANGE (1750 450);
DISPLAY INVISIBLE (1750 450);
FORCEPROP 1 LAST BODY_TYPE PLUMBING
J 0
(1705 407);
DISPLAY 0.340426 (1705 407);
PAINT GREEN (1705 407);
DISPLAY INVISIBLE (1705 407);
FORCEPROP 1 LAST HDL_POWER P3V3_STBY
J 0
(1450 325);
DISPLAY 0.872340 (1450 325);
PAINT ORANGE (1450 325);
DISPLAY INVISIBLE (1450 325);
FORCEADD DIODE..1
R 2
(1000 675);
FORCEPROP 2 LAST CDS_LOCATION CR9P2
J 2
(1027 831);
DISPLAY 0.617021 (1027 831);
PAINT AQUA (1027 831);
DISPLAY INVISIBLE (1027 831);
FORCEPROP 2 LAST SEC 1
J 0
(1025 950);
DISPLAY 0.680851 (1025 950);
PAINT MONO (1025 950);
DISPLAY INVISIBLE (1025 950);
FORCEPROP 2 LAST SEC_TYPE SMLF
J 0
(1025 950);
DISPLAY 1.021277 (1025 950);
PAINT ORANGE (1025 950);
DISPLAY INVISIBLE (1025 950);
FORCEPROP 1 LAST PATH I213
J 2
(1020 885);
DISPLAY 0.978723 (1020 885);
PAINT PINK (1020 885);
DISPLAY INVISIBLE (1020 885);
FORCEPROP 2 LAST CDS_LIB mstr_discrete
J 2
(1000 675);
PAINT ORANGE (1000 675);
DISPLAY INVISIBLE (1000 675);
FORCEPROP 1 LAST LOCATION CR9P2
J 2
(1027 831);
DISPLAY 0.617021 (1027 831);
PAINT AQUA (1027 831);
FORCEPROP 1 LAST PART_NUMBER C73510-001
J 2
(1025 775);
DISPLAY 0.617021 (1025 775);
PAINT BLUE (1025 775);
FORCEPROP 1 LASTPIN (900 675) $PN 1
J 2
(935 685);
DISPLAY 0.617021 (935 685);
PAINT AQUA (935 685);
FORCEPROP 1 LAST VALUE BAT54WS
J 2
(1025 550);
DISPLAY 0.617021 (1025 550);
PAINT SKYBLUE (1025 550);
FORCEPROP 1 LASTPIN (1100 675) $PN 2
J 0
(1065 685);
DISPLAY 0.617021 (1065 685);
PAINT AQUA (1065 685);
FORCEPROP 1 LAST PACK_TYPE SMLF
J 2
(1225 485);
DISPLAY 0.617021 (1225 485);
PAINT SKYBLUE (1225 485);
FORCEPROP 1 LAST MATERIAL IC
J 2
(1025 497);
DISPLAY 0.617021 (1025 497);
PAINT SKYBLUE (1025 497);
FORCEADD DIODE..1
R 2
(1050 175);
FORCEPROP 2 LAST CDS_LIB mstr_discrete
J 2
(1050 175);
PAINT ORANGE (1050 175);
DISPLAY INVISIBLE (1050 175);
FORCEPROP 2 LAST SEC_TYPE SMLF
J 0
(1075 450);
DISPLAY 1.021277 (1075 450);
PAINT ORANGE (1075 450);
DISPLAY INVISIBLE (1075 450);
FORCEPROP 2 LAST SEC 1
J 0
(1075 450);
DISPLAY 0.680851 (1075 450);
PAINT MONO (1075 450);
DISPLAY INVISIBLE (1075 450);
FORCEPROP 2 LAST CDS_LOCATION CR9P1
J 2
(1077 331);
DISPLAY 0.617021 (1077 331);
PAINT AQUA (1077 331);
DISPLAY INVISIBLE (1077 331);
FORCEPROP 1 LAST PATH I214
J 2
(1070 385);
DISPLAY 0.978723 (1070 385);
PAINT PINK (1070 385);
DISPLAY INVISIBLE (1070 385);
FORCEPROP 1 LAST PACK_TYPE SMLF
J 2
(1300 10);
DISPLAY 0.617021 (1300 10);
PAINT SKYBLUE (1300 10);
FORCEPROP 1 LASTPIN (1150 175) $PN 2
J 0
(1115 185);
DISPLAY 0.617021 (1115 185);
PAINT AQUA (1115 185);
FORCEPROP 1 LAST VALUE BAT54WS
J 2
(1075 50);
DISPLAY 0.617021 (1075 50);
PAINT SKYBLUE (1075 50);
FORCEPROP 1 LAST MATERIAL IC
J 2
(1075 -3);
DISPLAY 0.617021 (1075 -3);
PAINT SKYBLUE (1075 -3);
FORCEPROP 1 LAST PART_NUMBER C73510-001
J 2
(1075 275);
DISPLAY 0.617021 (1075 275);
PAINT BLUE (1075 275);
FORCEPROP 1 LASTPIN (950 175) $PN 1
J 2
(985 185);
DISPLAY 0.617021 (985 185);
PAINT AQUA (985 185);
FORCEPROP 1 LAST LOCATION CR9P1
J 2
(1077 331);
DISPLAY 0.617021 (1077 331);
PAINT AQUA (1077 331);
FORCEADD RES..2
(1500 1125);
FORCEPROP 2 LAST SEC_TYPE 0402
J 0
(1550 1350);
DISPLAY 1.021277 (1550 1350);
PAINT ORANGE (1550 1350);
DISPLAY INVISIBLE (1550 1350);
FORCEPROP 2 LAST SEC 1
J 0
(1550 1350);
DISPLAY 0.680851 (1550 1350);
PAINT MONO (1550 1350);
DISPLAY INVISIBLE (1550 1350);
FORCEPROP 2 LAST CDS_LOCATION R9P5
J 0
(1545 1250);
DISPLAY 0.617021 (1545 1250);
PAINT AQUA (1545 1250);
DISPLAY INVISIBLE (1545 1250);
FORCEPROP 1 LAST PATH I215
J 0
(1550 1300);
DISPLAY 0.978723 (1550 1300);
PAINT WHITE (1550 1300);
DISPLAY INVISIBLE (1550 1300);
FORCEPROP 2 LAST ROOM HOT_SWAP
J 0
(1550 1300);
PAINT MONO (1550 1300);
DISPLAY INVISIBLE (1550 1300);
FORCEPROP 2 LAST CDS_LIB mstr_discrete
J 0
(1500 1125);
PAINT ORANGE (1500 1125);
DISPLAY INVISIBLE (1500 1125);
FORCEPROP 1 LAST LOCATION R9P5
J 0
(1545 1250);
DISPLAY 0.617021 (1545 1250);
PAINT AQUA (1545 1250);
FORCEPROP 1 LAST VALUE 10.0K
J 0
(1545 1200);
DISPLAY 0.617021 (1545 1200);
PAINT SKYBLUE (1545 1200);
FORCEPROP 1 LAST TOLERANCE 1%
J 0
(1545 1150);
DISPLAY 0.617021 (1545 1150);
PAINT SKYBLUE (1545 1150);
FORCEPROP 1 LAST MATERIAL CHIP
J 0
(1540 1050);
DISPLAY 0.617021 (1540 1050);
PAINT SKYBLUE (1540 1050);
FORCEPROP 1 LAST WATTAGE 1/16W
J 0
(1540 1100);
DISPLAY 0.617021 (1540 1100);
PAINT SKYBLUE (1540 1100);
FORCEPROP 1 LASTPIN (1500 1225) $PN 1
J 0
(1505 1187);
DISPLAY 0.617021 (1505 1187);
PAINT ORANGE (1505 1187);
FORCEPROP 1 LASTPIN (1500 1025) $PN 2
J 0
(1505 1035);
DISPLAY 0.617021 (1505 1035);
PAINT ORANGE (1505 1035);
FORCEPROP 1 LAST PART_NUMBER G21796-016
J 0
(1540 1000);
DISPLAY 0.617021 (1540 1000);
PAINT BLUE (1540 1000);
FORCEPROP 1 LAST PACK_TYPE 0402
J 0
(1540 950);
DISPLAY 0.617021 (1540 950);
PAINT SKYBLUE (1540 950);
FORCEADD P3V3_STBY..1
(1500 1400);
FORCEPROP 3 LASTPIN (1500 1350) SIG_NAME P3V3_STBY\g
J 0
(1510 1360);
DISPLAY 0.659574 (1510 1360);
PAINT MONO (1510 1360);
DISPLAY INVISIBLE (1510 1360);
FORCEPROP 1 LAST VOLTAGE +3.3V
J 0
(1700 1550);
DISPLAY 1.021277 (1700 1550);
PAINT SKYBLUE (1700 1550);
DISPLAY INVISIBLE (1700 1550);
FORCEPROP 1 LAST SIZE 1B
J 0
(1545 1422);
DISPLAY 0.340426 (1545 1422);
PAINT GREEN (1545 1422);
DISPLAY INVISIBLE (1545 1422);
FORCEPROP 1 LAST PATH I216
J 0
(1545 1402);
DISPLAY 0.340426 (1545 1402);
PAINT GREEN (1545 1402);
DISPLAY INVISIBLE (1545 1402);
FORCEPROP 2 LAST CDS_LIB mstr_symbols
J 0
(1500 1400);
PAINT ORANGE (1500 1400);
DISPLAY INVISIBLE (1500 1400);
FORCEPROP 1 LAST BODY_TYPE PLUMBING
J 0
(1455 1357);
DISPLAY 0.340426 (1455 1357);
PAINT GREEN (1455 1357);
DISPLAY INVISIBLE (1455 1357);
FORCEPROP 1 LAST HDL_POWER P3V3_STBY
J 0
(1200 1275);
DISPLAY 0.872340 (1200 1275);
PAINT ORANGE (1200 1275);
DISPLAY INVISIBLE (1200 1275);
FORCEADD AGND0..1
(-4400 -650);
FORCEPROP 3 LASTPIN (-4400 -600) SIG_NAME AGND_HSC\g
J 0
(-4390 -590);
DISPLAY 0.659574 (-4390 -590);
PAINT MONO (-4390 -590);
DISPLAY INVISIBLE (-4390 -590);
FORCEPROP 1 LAST PATH I217
J 0
(-4325 -650);
DISPLAY 0.872340 (-4325 -650);
PAINT AQUA (-4325 -650);
DISPLAY INVISIBLE (-4325 -650);
FORCEPROP 2 LAST ROOM VR_P3V3
J 0
(-4425 -675);
PAINT ORANGE (-4425 -675);
DISPLAY INVISIBLE (-4425 -675);
FORCEPROP 2 LAST CDS_LIB mstr_symbols
J 0
(-4400 -650);
PAINT ORANGE (-4400 -650);
DISPLAY INVISIBLE (-4400 -650);
FORCEPROP 2 LAST BOM_COST MIO_VRD_MAIN
J 0
(-4375 -675);
PAINT ORANGE (-4375 -675);
DISPLAY INVISIBLE (-4375 -675);
FORCEPROP 1 LAST VOLTAGE 0
J 0
(-4400 -650);
PAINT SKYBLUE (-4400 -650);
DISPLAY INVISIBLE (-4400 -650);
FORCEPROP 1 LAST BODY_TYPE PLUMBING
J 0
(-4445 -693);
DISPLAY 0.340426 (-4445 -693);
PAINT GREEN (-4445 -693);
DISPLAY INVISIBLE (-4445 -693);
FORCEPROP 1 LAST HDL_POWER AGND_HSC
J 1
(-4400 -700);
DISPLAY 0.617021 (-4400 -700);
PAINT GREEN (-4400 -700);
FORCEADD RES..2
(-3950 -475);
FORCEPROP 2 LAST SEC_TYPE 0402
J 0
(-3900 -250);
DISPLAY 1.021277 (-3900 -250);
PAINT ORANGE (-3900 -250);
DISPLAY INVISIBLE (-3900 -250);
FORCEPROP 2 LAST SEC 1
J 0
(-3900 -250);
DISPLAY 0.680851 (-3900 -250);
PAINT MONO (-3900 -250);
DISPLAY INVISIBLE (-3900 -250);
FORCEPROP 1 LAST PATH I218
J 0
(-3900 -300);
DISPLAY 0.978723 (-3900 -300);
PAINT WHITE (-3900 -300);
DISPLAY INVISIBLE (-3900 -300);
FORCEPROP 2 LAST CDS_LOCATION R9P12
J 0
(-3905 -350);
DISPLAY 0.617021 (-3905 -350);
PAINT AQUA (-3905 -350);
DISPLAY INVISIBLE (-3905 -350);
FORCEPROP 2 LAST CDS_LIB mstr_discrete
J 0
(-3950 -475);
PAINT ORANGE (-3950 -475);
DISPLAY INVISIBLE (-3950 -475);
FORCEPROP 2 LAST ROOM HOT_SWAP
J 0
(-3900 -300);
PAINT MONO (-3900 -300);
DISPLAY INVISIBLE (-3900 -300);
FORCEPROP 1 LAST LOCATION R9P12
J 0
(-3905 -350);
DISPLAY 0.617021 (-3905 -350);
PAINT AQUA (-3905 -350);
FORCEPROP 1 LAST VALUE 4.99K
J 0
(-3905 -400);
DISPLAY 0.617021 (-3905 -400);
PAINT SKYBLUE (-3905 -400);
FORCEPROP 1 LAST WATTAGE 1/16W
J 0
(-3910 -500);
DISPLAY 0.617021 (-3910 -500);
PAINT SKYBLUE (-3910 -500);
FORCEPROP 1 LAST TOLERANCE 1%
J 0
(-3905 -450);
DISPLAY 0.617021 (-3905 -450);
PAINT SKYBLUE (-3905 -450);
FORCEPROP 1 LASTPIN (-3950 -375) $PN 1
J 0
(-3945 -413);
DISPLAY 0.617021 (-3945 -413);
PAINT ORANGE (-3945 -413);
FORCEPROP 1 LAST PART_NUMBER G21796-013
J 0
(-3910 -600);
DISPLAY 0.617021 (-3910 -600);
PAINT BLUE (-3910 -600);
FORCEPROP 1 LAST PACK_TYPE 0402
J 0
(-3910 -650);
DISPLAY 0.617021 (-3910 -650);
PAINT SKYBLUE (-3910 -650);
FORCEPROP 1 LAST MATERIAL CHIP
J 0
(-3910 -550);
DISPLAY 0.617021 (-3910 -550);
PAINT SKYBLUE (-3910 -550);
FORCEPROP 1 LASTPIN (-3950 -575) $PN 2
J 0
(-3945 -565);
DISPLAY 0.617021 (-3945 -565);
PAINT ORANGE (-3945 -565);
FORCEADD AGND0..1
(-3950 -675);
FORCEPROP 3 LASTPIN (-3950 -625) SIG_NAME AGND_HSC\g
J 0
(-3940 -615);
DISPLAY 0.659574 (-3940 -615);
PAINT MONO (-3940 -615);
DISPLAY INVISIBLE (-3940 -615);
FORCEPROP 2 LAST CDS_LIB mstr_symbols
J 0
(-3950 -675);
PAINT ORANGE (-3950 -675);
DISPLAY INVISIBLE (-3950 -675);
FORCEPROP 1 LAST PATH I219
J 0
(-3875 -675);
DISPLAY 0.872340 (-3875 -675);
PAINT AQUA (-3875 -675);
DISPLAY INVISIBLE (-3875 -675);
FORCEPROP 1 LAST VOLTAGE 0
J 0
(-3950 -675);
PAINT SKYBLUE (-3950 -675);
DISPLAY INVISIBLE (-3950 -675);
FORCEPROP 2 LAST BOM_COST MIO_VRD_MAIN
J 0
(-3925 -700);
PAINT ORANGE (-3925 -700);
DISPLAY INVISIBLE (-3925 -700);
FORCEPROP 2 LAST ROOM VR_P3V3
J 0
(-3975 -700);
PAINT ORANGE (-3975 -700);
DISPLAY INVISIBLE (-3975 -700);
FORCEPROP 1 LAST BODY_TYPE PLUMBING
J 0
(-3995 -718);
DISPLAY 0.340426 (-3995 -718);
PAINT GREEN (-3995 -718);
DISPLAY INVISIBLE (-3995 -718);
FORCEPROP 1 LAST HDL_POWER AGND_HSC
J 1
(-3950 -725);
DISPLAY 0.617021 (-3950 -725);
PAINT GREEN (-3950 -725);
FORCEADD DIODE..1
R 1
(2750 3275);
FORCEPROP 2 LAST SEC 1
J 0
(2800 3400);
DISPLAY 0.680851 (2800 3400);
PAINT MONO (2800 3400);
DISPLAY INVISIBLE (2800 3400);
FORCEPROP 2 LAST SEC_TYPE SM
J 0
(2800 3400);
DISPLAY 1.021277 (2800 3400);
PAINT ORANGE (2800 3400);
DISPLAY INVISIBLE (2800 3400);
FORCEPROP 2 LAST CDS_LIB mstr_discrete
J 0
(2750 3275);
PAINT ORANGE (2750 3275);
DISPLAY INVISIBLE (2750 3275);
FORCEPROP 1 LAST PATH I220
R 1
J 0
(2540 3255);
DISPLAY 0.978723 (2540 3255);
PAINT PINK (2540 3255);
DISPLAY INVISIBLE (2540 3255);
FORCEPROP 1 LAST MATERIAL EMPTY
R 1
J 0
(2928 3250);
DISPLAY 0.617021 (2928 3250);
PAINT RED (2928 3250);
FORCEPROP 1 LAST VALUE MBRS340T3G
R 1
J 0
(2875 3250);
DISPLAY 0.617021 (2875 3250);
PAINT SKYBLUE (2875 3250);
FORCEPROP 1 LAST PACK_TYPE SM
R 1
J 0
(2990 3250);
DISPLAY 0.617021 (2990 3250);
PAINT SKYBLUE (2990 3250);
FORCEPROP 1 LASTPIN (2750 3375) $PN 1
R 1
J 0
(2740 3340);
DISPLAY 0.617021 (2740 3340);
PAINT AQUA (2740 3340);
FORCEPROP 1 LAST LOCATION CR1F5
R 1
J 0
(2594 3248);
DISPLAY 0.617021 (2594 3248);
PAINT AQUA (2594 3248);
FORCEPROP 1 LAST PART_NUMBER C81983-002
R 1
J 0
(2650 3200);
DISPLAY 0.617021 (2650 3200);
PAINT BLUE (2650 3200);
FORCEPROP 1 LASTPIN (2750 3175) $PN 2
R 1
J 2
(2740 3210);
DISPLAY 0.617021 (2740 3210);
PAINT AQUA (2740 3210);
FORCEADD GND..1
(2750 3000);
FORCEPROP 3 LASTPIN (2750 3050) SIG_NAME GND\g
J 0
(2760 3060);
DISPLAY 0.659574 (2760 3060);
PAINT MONO (2760 3060);
DISPLAY INVISIBLE (2760 3060);
FORCEPROP 1 LAST VOLTAGE 0.0V
J 0
(2705 2957);
DISPLAY 0.340426 (2705 2957);
PAINT SKYBLUE (2705 2957);
DISPLAY INVISIBLE (2705 2957);
FORCEPROP 1 LAST SIZE 1B
J 0
(2825 2950);
DISPLAY 0.872340 (2825 2950);
PAINT AQUA (2825 2950);
DISPLAY INVISIBLE (2825 2950);
FORCEPROP 2 LAST CDS_LIB mstr_symbols
J 0
(2750 3000);
PAINT ORANGE (2750 3000);
DISPLAY INVISIBLE (2750 3000);
FORCEPROP 1 LAST PATH I221
J 0
(2825 3000);
DISPLAY 0.872340 (2825 3000);
PAINT AQUA (2825 3000);
DISPLAY INVISIBLE (2825 3000);
FORCEPROP 1 LAST BODY_TYPE PLUMBING
J 0
(2705 2957);
DISPLAY 0.340426 (2705 2957);
PAINT GREEN (2705 2957);
DISPLAY INVISIBLE (2705 2957);
FORCEPROP 1 LAST HDL_POWER GND
J 0
(2750 3150);
DISPLAY 0.872340 (2750 3150);
PAINT GREEN (2750 3150);
DISPLAY INVISIBLE (2750 3150);
FORCEADD RES..2
R 2
(-3950 200);
FORCEPROP 2 LAST CDS_SEC 1
J 0
(-4000 425);
PAINT MONO (-4000 425);
DISPLAY INVISIBLE (-4000 425);
FORCEPROP 2 LAST $SEC 1
J 0
(-4000 425);
PAINT MONO (-4000 425);
DISPLAY INVISIBLE (-4000 425);
FORCEPROP 1 LAST PATH I222
J 2
(-4000 375);
DISPLAY 0.978723 (-4000 375);
PAINT WHITE (-4000 375);
DISPLAY INVISIBLE (-4000 375);
FORCEPROP 2 LAST ROOM HOT_SWAP
J 2
(-4000 375);
PAINT MONO (-4000 375);
DISPLAY INVISIBLE (-4000 375);
FORCEPROP 1 LASTPIN (-3950 300) $PN 1
J 2
(-3955 262);
DISPLAY 0.787234 (-3955 262);
PAINT ORANGE (-3955 262);
DISPLAY INVISIBLE (-3955 262);
FORCEPROP 2 LAST CDS_LIB mstr_discrete
J 2
(-3950 200);
PAINT ORANGE (-3950 200);
DISPLAY INVISIBLE (-3950 200);
FORCEPROP 1 LASTPIN (-3950 100) $PN 2
J 2
(-3955 110);
DISPLAY 0.787234 (-3955 110);
PAINT ORANGE (-3955 110);
DISPLAY INVISIBLE (-3955 110);
FORCEPROP 1 LAST TOLERANCE 1%
J 2
(-3995 225);
DISPLAY 0.617021 (-3995 225);
PAINT SKYBLUE (-3995 225);
FORCEPROP 1 LAST LOCATION R9P33
J 2
(-3995 325);
DISPLAY 0.617021 (-3995 325);
PAINT AQUA (-3995 325);
FORCEPROP 1 LAST PART_NUMBER G21796-010
J 2
(-3990 75);
DISPLAY 0.617021 (-3990 75);
PAINT BLUE (-3990 75);
FORCEPROP 1 LAST VALUE 100.0K
J 2
(-3995 275);
DISPLAY 0.617021 (-3995 275);
PAINT SKYBLUE (-3995 275);
FORCEPROP 1 LAST PACK_TYPE 0402
J 2
(-3990 25);
DISPLAY 0.617021 (-3990 25);
PAINT SKYBLUE (-3990 25);
FORCEPROP 1 LAST MATERIAL CHIP
J 2
(-3990 125);
DISPLAY 0.617021 (-3990 125);
PAINT SKYBLUE (-3990 125);
FORCEPROP 1 LAST WATTAGE 1/16W
J 2
(-3990 175);
DISPLAY 0.617021 (-3990 175);
PAINT SKYBLUE (-3990 175);
FORCEADD P12V_STBY..1
(-3950 700);
FORCEPROP 3 LASTPIN (-3950 650) SIG_NAME P12V_STBY\g
J 0
(-3940 660);
DISPLAY 0.659574 (-3940 660);
PAINT MONO (-3940 660);
DISPLAY INVISIBLE (-3940 660);
FORCEPROP 1 LAST VOLTAGE 12.0V
J 0
(-3995 657);
DISPLAY 0.340426 (-3995 657);
PAINT SKYBLUE (-3995 657);
DISPLAY INVISIBLE (-3995 657);
FORCEPROP 1 LAST SIZE 1B
J 0
(-3905 722);
DISPLAY 0.340426 (-3905 722);
PAINT GREEN (-3905 722);
DISPLAY INVISIBLE (-3905 722);
FORCEPROP 2 LAST CDS_LIB mstr_symbols
J 0
(-3950 700);
PAINT ORANGE (-3950 700);
DISPLAY INVISIBLE (-3950 700);
FORCEPROP 1 LAST PATH I223
J 0
(-3905 702);
DISPLAY 0.340426 (-3905 702);
PAINT GREEN (-3905 702);
DISPLAY INVISIBLE (-3905 702);
FORCEPROP 1 LAST BODY_TYPE PLUMBING
J 0
(-3995 657);
DISPLAY 0.340426 (-3995 657);
PAINT GREEN (-3995 657);
DISPLAY INVISIBLE (-3995 657);
FORCEPROP 1 LAST HDL_POWER P12V_STBY
J 0
(-4250 575);
DISPLAY 0.872340 (-4250 575);
PAINT ORANGE (-4250 575);
DISPLAY INVISIBLE (-4250 575);
FORCEADD OFFPAGE..2
(-2550 -50);
FORCEPROP 2 LAST PATH I224
J 0
(-2375 25);
DISPLAY 1.021277 (-2375 25);
PAINT ORANGE (-2375 25);
DISPLAY INVISIBLE (-2375 25);
FORCEPROP 2 LAST CDS_LIB mstr_standard
J 0
(-2550 -50);
PAINT ORANGE (-2550 -50);
DISPLAY INVISIBLE (-2550 -50);
FORCEPROP 1 LAST OFFPAGE TRUE
J 0
(-2225 -175);
DISPLAY 0.872340 (-2225 -175);
PAINT GREEN (-2225 -175);
DISPLAY INVISIBLE (-2225 -175);
FORCEPROP 1 LAST COMMENT_BODY TRUE
J 0
(-2595 -145);
DISPLAY 0.872340 (-2595 -145);
PAINT GREEN (-2595 -145);
DISPLAY INVISIBLE (-2595 -145);
FORCEPROP 2 LAST $XR0 196 
J 0
(-2361 -50);
DISPLAY 0.638298 (-2361 -50);
PAINT MONO (-2361 -50);
FORCEPROP 2 LAST $XR1 118 
J 0
(-2361 -86);
DISPLAY 0.638298 (-2361 -86);
PAINT MONO (-2361 -86);
FORCEPROP 2 LAST $XR3 183 
J 0
(-2121 -86);
DISPLAY 0.638298 (-2121 -86);
PAINT MONO (-2121 -86);
FORCEPROP 2 LAST $XR4 191 
J 0
(-2001 -86);
DISPLAY 0.638298 (-2001 -86);
PAINT MONO (-2001 -86);
FORCEPROP 2 LAST $XR2 157 
J 0
(-2241 -86);
DISPLAY 0.638298 (-2241 -86);
PAINT MONO (-2241 -86);
FORCEADD FET_N..8
(-1500 1675);
FORCEPROP 1 LASTPIN (-1700 1575) $PN 1
J 2
(-1697 1590);
DISPLAY 0.872340 (-1697 1590);
PAINT WHITE (-1697 1590);
DISPLAY INVISIBLE (-1697 1590);
FORCEPROP 1 LASTPIN (-1500 1875) $PN 3
J 2
(-1447 1840);
DISPLAY 0.872340 (-1447 1840);
PAINT WHITE (-1447 1840);
DISPLAY INVISIBLE (-1447 1840);
FORCEPROP 1 LASTPIN (-1500 1475) $PN 2
J 2
(-1442 1475);
DISPLAY 0.872340 (-1442 1475);
PAINT WHITE (-1442 1475);
DISPLAY INVISIBLE (-1442 1475);
FORCEPROP 1 LAST PACK_TYPE SOT23LF
J 0
(-1300 1525);
DISPLAY 0.978723 (-1300 1525);
PAINT SKYBLUE (-1300 1525);
DISPLAY INVISIBLE (-1300 1525);
FORCEPROP 0 LAST ROOM HOT_SWAP
J 0
(-1300 1775);
DISPLAY 1.021277 (-1300 1775);
PAINT ORANGE (-1300 1775);
DISPLAY INVISIBLE (-1300 1775);
FORCEPROP 1 LAST PATH I225
J 0
(-1300 1725);
DISPLAY 0.978723 (-1300 1725);
PAINT BLUE (-1300 1725);
DISPLAY INVISIBLE (-1300 1725);
FORCEPROP 2 LAST CDS_LIB mstr_discrete
J 0
(-1500 1675);
PAINT MONO (-1500 1675);
DISPLAY INVISIBLE (-1500 1675);
FORCEPROP 1 LAST PART_NUMBER C79254-001
J 0
(-1300 1475);
DISPLAY 0.617021 (-1300 1475);
PAINT BLUE (-1300 1475);
FORCEPROP 1 LAST MATERIAL FET
J 0
(-1300 1575);
DISPLAY 0.617021 (-1300 1575);
PAINT SKYBLUE (-1300 1575);
FORCEPROP 1 LAST VALUE 2N7002
J 0
(-1300 1625);
DISPLAY 0.617021 (-1300 1625);
PAINT SKYBLUE (-1300 1625);
FORCEPROP 1 LAST LOCATION Q6W1
J 0
(-1300 1675);
DISPLAY 0.617021 (-1300 1675);
PAINT AQUA (-1300 1675);
FORCEADD OFFPAGE..1
(-2350 1575);
FORCEPROP 2 LAST $XRERR ?
J 0
(-2746 1575);
DISPLAY 0.638298 (-2746 1575);
PAINT MONO (-2746 1575);
DISPLAY INVISIBLE (-2746 1575);
FORCEPROP 2 LAST $XRERR ?
J 0
(-2746 1575);
DISPLAY 0.638298 (-2746 1575);
PAINT MONO (-2746 1575);
DISPLAY INVISIBLE (-2746 1575);
FORCEPROP 2 LAST $XRERR ?
J 0
(-2746 1575);
DISPLAY 0.638298 (-2746 1575);
PAINT MONO (-2746 1575);
DISPLAY INVISIBLE (-2746 1575);
FORCEPROP 2 LAST $XRERR ?
J 0
(-2746 1575);
DISPLAY 0.638298 (-2746 1575);
PAINT MONO (-2746 1575);
DISPLAY INVISIBLE (-2746 1575);
FORCEPROP 2 LAST $XRERR ?
J 0
(-2746 1575);
DISPLAY 0.638298 (-2746 1575);
PAINT MONO (-2746 1575);
DISPLAY INVISIBLE (-2746 1575);
FORCEPROP 2 LAST $XRERR ?
J 0
(-2746 1575);
DISPLAY 0.638298 (-2746 1575);
PAINT MONO (-2746 1575);
DISPLAY INVISIBLE (-2746 1575);
FORCEPROP 2 LAST PATH I226
J 0
(-2600 1625);
DISPLAY 1.021277 (-2600 1625);
PAINT ORANGE (-2600 1625);
DISPLAY INVISIBLE (-2600 1625);
FORCEPROP 2 LAST CDS_LIB mstr_standard
J 0
(-2350 1575);
PAINT ORANGE (-2350 1575);
DISPLAY INVISIBLE (-2350 1575);
FORCEPROP 2 LAST $XRERR ?
J 0
(-2746 1575);
DISPLAY 0.638298 (-2746 1575);
PAINT MONO (-2746 1575);
DISPLAY INVISIBLE (-2746 1575);
FORCEPROP 1 LAST OFFPAGE TRUE
J 0
(-2025 1450);
DISPLAY 0.872340 (-2025 1450);
PAINT GREEN (-2025 1450);
DISPLAY INVISIBLE (-2025 1450);
FORCEPROP 1 LAST COMMENT_BODY TRUE
J 0
(-2225 1475);
DISPLAY 0.872340 (-2225 1475);
PAINT GREEN (-2225 1475);
DISPLAY INVISIBLE (-2225 1475);
FORCEPROP 2 LAST $XRERR ?
J 0
(-2746 1575);
DISPLAY 0.638298 (-2746 1575);
PAINT MONO (-2746 1575);
DISPLAY INVISIBLE (-2746 1575);
FORCEPROP 2 LAST $XRERR ?
J 0
(-2746 1575);
DISPLAY 0.638298 (-2746 1575);
PAINT MONO (-2746 1575);
DISPLAY INVISIBLE (-2746 1575);
FORCEPROP 2 LAST $XRERR ?
J 0
(-2746 1575);
DISPLAY 0.638298 (-2746 1575);
PAINT MONO (-2746 1575);
DISPLAY INVISIBLE (-2746 1575);
FORCEPROP 2 LAST $XRERR ?
J 0
(-2746 1575);
DISPLAY 0.638298 (-2746 1575);
PAINT MONO (-2746 1575);
DISPLAY INVISIBLE (-2746 1575);
FORCEPROP 2 LAST $XRERR ?
J 0
(-2746 1575);
DISPLAY 0.638298 (-2746 1575);
PAINT MONO (-2746 1575);
DISPLAY INVISIBLE (-2746 1575);
FORCEPROP 2 LAST $XR0 147 
J 0
(-2602 1575);
DISPLAY 0.638298 (-2602 1575);
PAINT MONO (-2602 1575);
FORCEPROP 2 LAST $XR1 ?
J 0
(-2722 1575);
DISPLAY 0.638298 (-2722 1575);
PAINT MONO (-2722 1575);
FORCEPROP 2 LAST $XR2 ?
J 0
(-2842 1575);
DISPLAY 0.638298 (-2842 1575);
PAINT MONO (-2842 1575);
FORCEADD GND..1
(-1500 1300);
FORCEPROP 3 LASTPIN (-1500 1350) SIG_NAME GND\g
J 0
(-1490 1360);
DISPLAY 0.659574 (-1490 1360);
PAINT MONO (-1490 1360);
DISPLAY INVISIBLE (-1490 1360);
FORCEPROP 2 LAST CDS_LIB mstr_symbols
J 0
(-1500 1300);
PAINT MONO (-1500 1300);
DISPLAY INVISIBLE (-1500 1300);
FORCEPROP 1 LAST PATH I227
J 0
(-1425 1300);
DISPLAY 0.872340 (-1425 1300);
PAINT AQUA (-1425 1300);
DISPLAY INVISIBLE (-1425 1300);
FORCEPROP 1 LAST VOLTAGE 0.0V
J 0
(-1545 1257);
DISPLAY 0.340426 (-1545 1257);
PAINT SKYBLUE (-1545 1257);
DISPLAY INVISIBLE (-1545 1257);
FORCEPROP 1 LAST SIZE 1B
J 0
(-1425 1250);
DISPLAY 0.872340 (-1425 1250);
PAINT AQUA (-1425 1250);
DISPLAY INVISIBLE (-1425 1250);
FORCEPROP 1 LAST BODY_TYPE PLUMBING
J 0
(-1545 1257);
DISPLAY 0.340426 (-1545 1257);
PAINT GREEN (-1545 1257);
DISPLAY INVISIBLE (-1545 1257);
FORCEPROP 1 LAST HDL_POWER GND
J 0
(-1500 1450);
DISPLAY 0.872340 (-1500 1450);
PAINT GREEN (-1500 1450);
DISPLAY INVISIBLE (-1500 1450);
FORCEADD RES..2
(-1950 1825);
FORCEPROP 1 LASTPIN (-1950 1925) $PN 1
J 0
(-1945 1887);
DISPLAY 0.787234 (-1945 1887);
PAINT ORANGE (-1945 1887);
DISPLAY INVISIBLE (-1945 1887);
FORCEPROP 1 LASTPIN (-1950 1725) $PN 2
J 0
(-1945 1735);
DISPLAY 0.787234 (-1945 1735);
PAINT ORANGE (-1945 1735);
DISPLAY INVISIBLE (-1945 1735);
FORCEPROP 2 LAST CDS_LIB mstr_discrete
J 0
(-1950 1825);
PAINT MONO (-1950 1825);
DISPLAY INVISIBLE (-1950 1825);
FORCEPROP 1 LAST PATH I229
J 0
(-1900 2000);
DISPLAY 0.978723 (-1900 2000);
PAINT WHITE (-1900 2000);
DISPLAY INVISIBLE (-1900 2000);
FORCEPROP 2 LAST ROOM PVCCIN_CPU1_VR
J 0
(-1900 2000);
DISPLAY 1.361702 (-1900 2000);
PAINT WHITE (-1900 2000);
DISPLAY INVISIBLE (-1900 2000);
FORCEPROP 1 LAST WATTAGE 1/16W
J 0
(-1910 1800);
DISPLAY 0.617021 (-1910 1800);
PAINT SKYBLUE (-1910 1800);
FORCEPROP 1 LAST VALUE 100.0K
J 0
(-1905 1900);
DISPLAY 0.617021 (-1905 1900);
PAINT SKYBLUE (-1905 1900);
FORCEPROP 1 LAST LOCATION R6W1
J 0
(-1905 1950);
DISPLAY 0.617021 (-1905 1950);
PAINT AQUA (-1905 1950);
FORCEPROP 1 LAST MATERIAL CHIP
J 0
(-1910 1750);
DISPLAY 0.617021 (-1910 1750);
PAINT SKYBLUE (-1910 1750);
FORCEPROP 1 LAST PART_NUMBER G21796-160
J 0
(-1910 1700);
DISPLAY 0.617021 (-1910 1700);
PAINT BLUE (-1910 1700);
FORCEPROP 1 LAST PACK_TYPE 0402
J 0
(-1910 1650);
DISPLAY 0.617021 (-1910 1650);
PAINT SKYBLUE (-1910 1650);
FORCEPROP 1 LAST TOLERANCE 1%
J 0
(-1905 1850);
DISPLAY 0.617021 (-1905 1850);
PAINT SKYBLUE (-1905 1850);
FORCEADD RES..2
(-1950 1425);
FORCEPROP 1 LASTPIN (-1950 1525) $PN 1
J 0
(-1945 1487);
DISPLAY 0.787234 (-1945 1487);
PAINT ORANGE (-1945 1487);
DISPLAY INVISIBLE (-1945 1487);
FORCEPROP 1 LASTPIN (-1950 1325) $PN 2
J 0
(-1945 1335);
DISPLAY 0.787234 (-1945 1335);
PAINT ORANGE (-1945 1335);
DISPLAY INVISIBLE (-1945 1335);
FORCEPROP 2 LAST CDS_LIB mstr_discrete
J 0
(-1950 1425);
PAINT MONO (-1950 1425);
DISPLAY INVISIBLE (-1950 1425);
FORCEPROP 1 LAST PATH I230
J 0
(-1900 1600);
DISPLAY 0.978723 (-1900 1600);
PAINT WHITE (-1900 1600);
DISPLAY INVISIBLE (-1900 1600);
FORCEPROP 2 LAST ROOM HOT_SWAP
J 0
(-1900 1600);
PAINT MONO (-1900 1600);
DISPLAY INVISIBLE (-1900 1600);
FORCEPROP 0 LAST STATUS NOPOP
J 0
(-2200 1350);
DISPLAY 1.021277 (-2200 1350);
PAINT ORANGE (-2200 1350);
FORCEPROP 1 LAST VALUE 10.0K
J 0
(-1905 1500);
DISPLAY 0.617021 (-1905 1500);
PAINT SKYBLUE (-1905 1500);
FORCEPROP 1 LAST TOLERANCE 1%
J 0
(-1905 1450);
DISPLAY 0.617021 (-1905 1450);
PAINT SKYBLUE (-1905 1450);
FORCEPROP 1 LAST PART_NUMBER G21796-016
J 0
(-1910 1300);
DISPLAY 0.617021 (-1910 1300);
PAINT BLUE (-1910 1300);
FORCEPROP 1 LAST MATERIAL CHIP
J 0
(-1910 1350);
DISPLAY 0.617021 (-1910 1350);
PAINT SKYBLUE (-1910 1350);
FORCEPROP 1 LAST PACK_TYPE 0402
J 0
(-1910 1250);
DISPLAY 0.617021 (-1910 1250);
PAINT SKYBLUE (-1910 1250);
FORCEPROP 1 LAST LOCATION R6W2
J 0
(-1905 1550);
DISPLAY 0.617021 (-1905 1550);
PAINT AQUA (-1905 1550);
FORCEPROP 1 LAST WATTAGE 1/16W
J 0
(-1910 1400);
DISPLAY 0.617021 (-1910 1400);
PAINT SKYBLUE (-1910 1400);
FORCEADD GND..1
(-1950 1225);
FORCEPROP 3 LASTPIN (-1950 1275) SIG_NAME GND\g
J 0
(-1940 1285);
DISPLAY 0.659574 (-1940 1285);
PAINT MONO (-1940 1285);
DISPLAY INVISIBLE (-1940 1285);
FORCEPROP 1 LAST SIZE 1B
J 0
(-1875 1175);
DISPLAY 0.872340 (-1875 1175);
PAINT AQUA (-1875 1175);
DISPLAY INVISIBLE (-1875 1175);
FORCEPROP 1 LAST VOLTAGE 0.0V
J 0
(-1995 1182);
DISPLAY 0.340426 (-1995 1182);
PAINT SKYBLUE (-1995 1182);
DISPLAY INVISIBLE (-1995 1182);
FORCEPROP 1 LAST PATH I231
J 0
(-1875 1225);
DISPLAY 0.872340 (-1875 1225);
PAINT AQUA (-1875 1225);
DISPLAY INVISIBLE (-1875 1225);
FORCEPROP 2 LAST CDS_LIB mstr_symbols
J 0
(-1950 1225);
PAINT MONO (-1950 1225);
DISPLAY INVISIBLE (-1950 1225);
FORCEPROP 1 LAST BODY_TYPE PLUMBING
J 0
(-1995 1182);
DISPLAY 0.340426 (-1995 1182);
PAINT GREEN (-1995 1182);
DISPLAY INVISIBLE (-1995 1182);
FORCEPROP 1 LAST HDL_POWER GND
J 0
(-1950 1375);
DISPLAY 0.872340 (-1950 1375);
PAINT GREEN (-1950 1375);
DISPLAY INVISIBLE (-1950 1375);
FORCEADD P3V3_STBY..1
(-1950 2050);
FORCEPROP 3 LASTPIN (-1950 2000) SIG_NAME P3V3_STBY\g
J 0
(-1940 2010);
DISPLAY 0.659574 (-1940 2010);
PAINT MONO (-1940 2010);
DISPLAY INVISIBLE (-1940 2010);
FORCEPROP 1 LAST VOLTAGE +3.3V
J 0
(-1750 2200);
DISPLAY 1.021277 (-1750 2200);
PAINT SKYBLUE (-1750 2200);
DISPLAY INVISIBLE (-1750 2200);
FORCEPROP 1 LAST SIZE 1B
J 0
(-1905 2072);
DISPLAY 0.340426 (-1905 2072);
PAINT GREEN (-1905 2072);
DISPLAY INVISIBLE (-1905 2072);
FORCEPROP 1 LAST PATH I232
J 0
(-1905 2052);
DISPLAY 0.340426 (-1905 2052);
PAINT GREEN (-1905 2052);
DISPLAY INVISIBLE (-1905 2052);
FORCEPROP 2 LAST CDS_LIB mstr_symbols
J 0
(-1950 2050);
PAINT MONO (-1950 2050);
DISPLAY INVISIBLE (-1950 2050);
FORCEPROP 1 LAST BODY_TYPE PLUMBING
J 0
(-1995 2007);
DISPLAY 0.340426 (-1995 2007);
PAINT GREEN (-1995 2007);
DISPLAY INVISIBLE (-1995 2007);
FORCEPROP 1 LAST HDL_POWER P3V3_STBY
J 0
(-2250 1925);
DISPLAY 0.872340 (-2250 1925);
PAINT ORANGE (-2250 1925);
DISPLAY INVISIBLE (-2250 1925);
FORCEADD SC22P50V2JN-4GP..1
(-700 -100);
FORCEPROP 0 LAST STATUS NOPOP
J 0
(-675 -200);
DISPLAY 0.638298 (-675 -200);
PAINT ORANGE (-675 -200);
FORCEPROP 1 LAST PACK_TYPE SMD-BCG
J 0
(-700 -100);
DISPLAY 0.617021 (-700 -100);
PAINT GREEN (-700 -100);
DISPLAY INVISIBLE (-700 -100);
FORCEPROP 1 LAST PART_NUMBER 78.22034.1FL
J 0
(-700 -100);
DISPLAY 0.617021 (-700 -100);
PAINT GREEN (-700 -100);
DISPLAY INVISIBLE (-700 -100);
FORCEPROP 2 LAST CDS_LIB w_hdl
J 0
(-700 -100);
PAINT MONO (-700 -100);
DISPLAY INVISIBLE (-700 -100);
FORCEPROP 1 LAST PATH I235
J 0
(-700 -100);
DISPLAY 0.617021 (-700 -100);
PAINT GREEN (-700 -100);
DISPLAY INVISIBLE (-700 -100);
FORCEPROP 1 LAST CDS_LMAN_SYM_OUTLINE -50,25,50,-25
J 0
(-700 -100);
DISPLAY 0.468085 (-700 -100);
PAINT GREEN (-700 -100);
DISPLAY INVISIBLE (-700 -100);
FORCEPROP 1 LAST VALUE SC22P50V2JN-4GP
J 0
(-675 -150);
DISPLAY 0.617021 (-675 -150);
PAINT GREEN (-675 -150);
FORCEPROP 1 LAST LOCATION C9W1
J 0
(-675 -70);
DISPLAY 0.617021 (-675 -70);
PAINT GREEN (-675 -70);
FORCEADD SC22P50V2JN-4GP..1
(-1050 175);
FORCEPROP 0 LAST STATUS NOPOP
J 0
(-1025 0);
DISPLAY 0.638298 (-1025 0);
PAINT ORANGE (-1025 0);
FORCEPROP 1 LAST CDS_LMAN_SYM_OUTLINE -50,25,50,-25
J 0
(-1050 175);
DISPLAY 0.468085 (-1050 175);
PAINT GREEN (-1050 175);
DISPLAY INVISIBLE (-1050 175);
FORCEPROP 1 LAST PATH I236
J 0
(-1050 175);
DISPLAY 0.617021 (-1050 175);
PAINT GREEN (-1050 175);
DISPLAY INVISIBLE (-1050 175);
FORCEPROP 2 LAST CDS_LIB w_hdl
J 0
(-1050 175);
PAINT MONO (-1050 175);
DISPLAY INVISIBLE (-1050 175);
FORCEPROP 1 LAST PART_NUMBER 78.22034.1FL
J 0
(-1050 175);
DISPLAY 0.617021 (-1050 175);
PAINT GREEN (-1050 175);
DISPLAY INVISIBLE (-1050 175);
FORCEPROP 1 LAST PACK_TYPE SMD-BCG
J 0
(-1050 175);
DISPLAY 0.617021 (-1050 175);
PAINT GREEN (-1050 175);
DISPLAY INVISIBLE (-1050 175);
FORCEPROP 1 LAST LOCATION C9W2
J 0
(-1025 205);
DISPLAY 0.617021 (-1025 205);
PAINT GREEN (-1025 205);
FORCEPROP 1 LAST VALUE SC22P50V2JN-4GP
J 0
(-1025 125);
DISPLAY 0.617021 (-1025 125);
PAINT GREEN (-1025 125);
FORCEADD AGND0..1
(-700 -250);
FORCEPROP 3 LASTPIN (-700 -200) SIG_NAME AGND_HSC\g
J 0
(-690 -190);
DISPLAY 0.659574 (-690 -190);
PAINT MONO (-690 -190);
DISPLAY INVISIBLE (-690 -190);
FORCEPROP 2 LAST CDS_LIB mstr_symbols
J 0
(-700 -250);
PAINT MONO (-700 -250);
DISPLAY INVISIBLE (-700 -250);
FORCEPROP 1 LAST PATH I237
J 0
(-625 -250);
DISPLAY 0.872340 (-625 -250);
PAINT AQUA (-625 -250);
DISPLAY INVISIBLE (-625 -250);
FORCEPROP 1 LAST VOLTAGE 0
J 0
(-700 -250);
PAINT SKYBLUE (-700 -250);
DISPLAY INVISIBLE (-700 -250);
FORCEPROP 2 LAST BOM_COST MIO_VRD_MAIN
J 0
(-675 -275);
PAINT ORANGE (-675 -275);
DISPLAY INVISIBLE (-675 -275);
FORCEPROP 2 LAST ROOM VR_P3V3
J 0
(-725 -275);
PAINT ORANGE (-725 -275);
DISPLAY INVISIBLE (-725 -275);
FORCEPROP 1 LAST BODY_TYPE PLUMBING
J 0
(-745 -293);
DISPLAY 0.340426 (-745 -293);
PAINT GREEN (-745 -293);
DISPLAY INVISIBLE (-745 -293);
FORCEPROP 1 LAST HDL_POWER AGND_HSC
J 1
(-700 -300);
DISPLAY 0.617021 (-700 -300);
PAINT GREEN (-700 -300);
FORCEADD AGND0..1
(-1050 -100);
FORCEPROP 3 LASTPIN (-1050 -50) SIG_NAME AGND_HSC\g
J 0
(-1040 -40);
DISPLAY 0.659574 (-1040 -40);
PAINT MONO (-1040 -40);
DISPLAY INVISIBLE (-1040 -40);
FORCEPROP 1 LAST VOLTAGE 0
J 0
(-1050 -100);
PAINT SKYBLUE (-1050 -100);
DISPLAY INVISIBLE (-1050 -100);
FORCEPROP 2 LAST BOM_COST MIO_VRD_MAIN
J 0
(-1025 -125);
PAINT ORANGE (-1025 -125);
DISPLAY INVISIBLE (-1025 -125);
FORCEPROP 2 LAST ROOM VR_P3V3
J 0
(-1075 -125);
PAINT ORANGE (-1075 -125);
DISPLAY INVISIBLE (-1075 -125);
FORCEPROP 1 LAST BODY_TYPE PLUMBING
J 0
(-1095 -143);
DISPLAY 0.340426 (-1095 -143);
PAINT GREEN (-1095 -143);
DISPLAY INVISIBLE (-1095 -143);
FORCEPROP 1 LAST PATH I238
J 0
(-975 -100);
DISPLAY 0.872340 (-975 -100);
PAINT AQUA (-975 -100);
DISPLAY INVISIBLE (-975 -100);
FORCEPROP 2 LAST CDS_LIB mstr_symbols
J 0
(-1050 -100);
PAINT MONO (-1050 -100);
DISPLAY INVISIBLE (-1050 -100);
FORCEPROP 1 LAST HDL_POWER AGND_HSC
J 1
(-1050 -150);
DISPLAY 0.617021 (-1050 -150);
PAINT GREEN (-1050 -150);
FORCEADD 232KR2F-2-GP..1
R 1
(-800 1950);
FORCEPROP 1 LAST PACK_TYPE SMD-RG1
R 1
J 0
(-800 1950);
DISPLAY 0.617021 (-800 1950);
PAINT GREEN (-800 1950);
DISPLAY INVISIBLE (-800 1950);
FORCEPROP 1 LAST PART_NUMBER 64.23235.L0L
R 1
J 0
(-800 1950);
DISPLAY 0.617021 (-800 1950);
PAINT GREEN (-800 1950);
DISPLAY INVISIBLE (-800 1950);
FORCEPROP 2 LAST CDS_LIB w_hdl
R 1
J 0
(-800 1950);
PAINT MONO (-800 1950);
DISPLAY INVISIBLE (-800 1950);
FORCEPROP 1 LAST PATH I239
R 1
J 0
(-800 1950);
DISPLAY 0.617021 (-800 1950);
PAINT GREEN (-800 1950);
DISPLAY INVISIBLE (-800 1950);
FORCEPROP 1 LAST CDS_LMAN_SYM_OUTLINE -50,75,50,-75
R 1
J 0
(-800 1950);
DISPLAY 0.468085 (-800 1950);
PAINT GREEN (-800 1950);
DISPLAY INVISIBLE (-800 1950);
FORCEPROP 1 LAST VALUE 232KR2F-2-GP
J 0
(-900 2000);
DISPLAY 0.617021 (-900 2000);
PAINT GREEN (-900 2000);
FORCEPROP 1 LAST LOCATION R6W3
J 0
(-900 2050);
DISPLAY 0.617021 (-900 2050);
PAINT GREEN (-900 2050);
FORCEADD CAP_A..1
(-1025 3425);
FORCEPROP 2 LAST SEC 1
J 0
(-975 3625);
DISPLAY 0.680851 (-975 3625);
PAINT MONO (-975 3625);
DISPLAY INVISIBLE (-975 3625);
FORCEPROP 2 LAST SEC_TYPE 0402V
J 0
(-975 3625);
DISPLAY 1.021277 (-975 3625);
PAINT ORANGE (-975 3625);
DISPLAY INVISIBLE (-975 3625);
FORCEPROP 0 LAST ROOM HOT_SWAP
J 2
(-975 3575);
DISPLAY 1.021277 (-975 3575);
PAINT ORANGE (-975 3575);
DISPLAY INVISIBLE (-975 3575);
FORCEPROP 1 LAST PATH I36
J 0
(-975 3575);
DISPLAY 0.978723 (-975 3575);
PAINT WHITE (-975 3575);
DISPLAY INVISIBLE (-975 3575);
FORCEPROP 2 LAST CDS_LOCATION C9P17
J 0
(-975 3525);
DISPLAY 0.617021 (-975 3525);
PAINT AQUA (-975 3525);
DISPLAY INVISIBLE (-975 3525);
FORCEPROP 2 LAST CDS_LIB dev_discrete
J 0
(-1025 3425);
PAINT ORANGE (-1025 3425);
DISPLAY INVISIBLE (-1025 3425);
FORCEPROP 1 LAST PART_NUMBER A36096-030
J 0
(-975 3275);
DISPLAY 0.617021 (-975 3275);
PAINT BLUE (-975 3275);
FORCEPROP 1 LAST LOCATION C9P17
J 0
(-975 3525);
DISPLAY 0.617021 (-975 3525);
PAINT AQUA (-975 3525);
FORCEPROP 1 LAST VALUE 0.1UF
J 0
(-975 3475);
DISPLAY 0.617021 (-975 3475);
PAINT SKYBLUE (-975 3475);
FORCEPROP 1 LAST TOLERANCE 10%
J 0
(-975 3375);
DISPLAY 0.617021 (-975 3375);
PAINT SKYBLUE (-975 3375);
FORCEPROP 1 LAST VOLTAGE 16V
J 0
(-975 3425);
DISPLAY 0.617021 (-975 3425);
PAINT SKYBLUE (-975 3425);
FORCEPROP 1 LASTPIN (-1025 3525) $PN 1
J 0
(-1015 3505);
DISPLAY 0.617021 (-1015 3505);
PAINT ORANGE (-1015 3505);
FORCEPROP 1 LAST MATERIAL EMPTY
J 0
(-975 3325);
DISPLAY 0.617021 (-975 3325);
PAINT RED (-975 3325);
FORCEPROP 1 LASTPIN (-1025 3325) $PN 2
J 0
(-1015 3305);
DISPLAY 0.617021 (-1015 3305);
PAINT ORANGE (-1015 3305);
FORCEPROP 1 LAST PACK_TYPE 0402V
J 0
(-975 3225);
DISPLAY 0.617021 (-975 3225);
PAINT SKYBLUE (-975 3225);
FORCEADD OFFPAGE..4
R 2
(-1125 3625);
FORCEPROP 2 LAST PATH I37
J 0
(-1075 3700);
DISPLAY 1.021277 (-1075 3700);
PAINT ORANGE (-1075 3700);
DISPLAY INVISIBLE (-1075 3700);
FORCEPROP 2 LAST CDS_LIB mstr_standard
J 0
(-1125 3625);
PAINT ORANGE (-1125 3625);
DISPLAY INVISIBLE (-1125 3625);
FORCEPROP 1 LAST OFFPAGE TRUE
J 2
(-1450 3500);
PAINT GREEN (-1450 3500);
DISPLAY INVISIBLE (-1450 3500);
FORCEPROP 1 LAST COMMENT_BODY TRUE
J 2
(-1100 3525);
DISPLAY 1.872340 (-1100 3525);
PAINT GREEN (-1100 3525);
DISPLAY INVISIBLE (-1100 3525);
FORCEPROP 2 LAST $XR0 199 
J 0
(-1377 3625);
DISPLAY 0.638298 (-1377 3625);
PAINT MONO (-1377 3625);
FORCEADD OFFPAGE..4
R 2
(-1150 3150);
FORCEPROP 2 LAST PATH I38
J 0
(-1100 3225);
DISPLAY 1.021277 (-1100 3225);
PAINT ORANGE (-1100 3225);
DISPLAY INVISIBLE (-1100 3225);
FORCEPROP 2 LAST CDS_LIB mstr_standard
J 0
(-1150 3150);
PAINT ORANGE (-1150 3150);
DISPLAY INVISIBLE (-1150 3150);
FORCEPROP 1 LAST OFFPAGE TRUE
J 2
(-1475 3025);
PAINT GREEN (-1475 3025);
DISPLAY INVISIBLE (-1475 3025);
FORCEPROP 1 LAST COMMENT_BODY TRUE
J 2
(-1125 3050);
DISPLAY 1.872340 (-1125 3050);
PAINT GREEN (-1125 3050);
DISPLAY INVISIBLE (-1125 3050);
FORCEPROP 2 LAST $XR0 199 
J 0
(-1402 3150);
DISPLAY 0.638298 (-1402 3150);
PAINT MONO (-1402 3150);
FORCEADD AGND0..1
(-1025 3225);
FORCEPROP 3 LASTPIN (-1025 3275) SIG_NAME AGND_HSC\g
J 0
(-1015 3285);
DISPLAY 0.659574 (-1015 3285);
PAINT MONO (-1015 3285);
DISPLAY INVISIBLE (-1015 3285);
FORCEPROP 2 LAST BOM_COST MIO_VRD_MAIN
J 0
(-1000 3200);
PAINT ORANGE (-1000 3200);
DISPLAY INVISIBLE (-1000 3200);
FORCEPROP 1 LAST PATH I39
J 0
(-950 3225);
DISPLAY 0.872340 (-950 3225);
PAINT AQUA (-950 3225);
DISPLAY INVISIBLE (-950 3225);
FORCEPROP 2 LAST CDS_LIB mstr_symbols
J 0
(-1025 3225);
PAINT ORANGE (-1025 3225);
DISPLAY INVISIBLE (-1025 3225);
FORCEPROP 1 LAST VOLTAGE 0
J 0
(-1025 3225);
PAINT SKYBLUE (-1025 3225);
DISPLAY INVISIBLE (-1025 3225);
FORCEPROP 2 LAST ROOM VR_P3V3
J 0
(-1050 3200);
PAINT ORANGE (-1050 3200);
DISPLAY INVISIBLE (-1050 3200);
FORCEPROP 1 LAST BODY_TYPE PLUMBING
J 0
(-1070 3182);
DISPLAY 0.340426 (-1070 3182);
PAINT GREEN (-1070 3182);
DISPLAY INVISIBLE (-1070 3182);
FORCEPROP 1 LAST HDL_POWER AGND_HSC
J 1
(-1025 3175);
DISPLAY 0.617021 (-1025 3175);
PAINT GREEN (-1025 3175);
FORCEADD CAP_A..1
(-675 3000);
FORCEPROP 2 LAST CDS_SEC 1
J 0
(-625 3200);
DISPLAY 1.021277 (-625 3200);
PAINT ORANGE (-625 3200);
DISPLAY INVISIBLE (-625 3200);
FORCEPROP 2 LAST CDS_LOCATION C9P16
J 0
(-625 3100);
DISPLAY 0.617021 (-625 3100);
PAINT AQUA (-625 3100);
DISPLAY INVISIBLE (-625 3100);
FORCEPROP 0 LAST ROOM HOT_SWAP
J 2
(-625 3150);
DISPLAY 1.021277 (-625 3150);
PAINT ORANGE (-625 3150);
DISPLAY INVISIBLE (-625 3150);
FORCEPROP 1 LAST PATH I40
J 0
(-625 3150);
DISPLAY 0.978723 (-625 3150);
PAINT WHITE (-625 3150);
DISPLAY INVISIBLE (-625 3150);
FORCEPROP 1 LASTPIN (-675 3100) $PN 1
J 0
(-665 3080);
DISPLAY 0.787234 (-665 3080);
PAINT ORANGE (-665 3080);
DISPLAY INVISIBLE (-665 3080);
FORCEPROP 2 LAST CDS_LIB dev_discrete
J 0
(-675 3000);
PAINT ORANGE (-675 3000);
DISPLAY INVISIBLE (-675 3000);
FORCEPROP 1 LASTPIN (-675 2900) $PN 2
J 0
(-665 2880);
DISPLAY 0.787234 (-665 2880);
PAINT ORANGE (-665 2880);
DISPLAY INVISIBLE (-665 2880);
FORCEPROP 1 LAST PACK_TYPE 0402V
J 0
(-625 2800);
DISPLAY 0.617021 (-625 2800);
PAINT SKYBLUE (-625 2800);
FORCEPROP 1 LAST PART_NUMBER A36096-030
J 0
(-625 2850);
DISPLAY 0.617021 (-625 2850);
PAINT BLUE (-625 2850);
FORCEPROP 1 LAST VOLTAGE 16V
J 0
(-625 3000);
DISPLAY 0.617021 (-625 3000);
PAINT SKYBLUE (-625 3000);
FORCEPROP 1 LAST TOLERANCE 10%
J 0
(-625 2950);
DISPLAY 0.617021 (-625 2950);
PAINT SKYBLUE (-625 2950);
FORCEPROP 1 LAST MATERIAL EMPTY
J 0
(-625 2900);
DISPLAY 0.617021 (-625 2900);
PAINT RED (-625 2900);
FORCEPROP 1 LAST LOCATION C9P16
J 0
(-625 3100);
DISPLAY 0.617021 (-625 3100);
PAINT AQUA (-625 3100);
FORCEPROP 1 LAST VALUE 0.1UF
J 0
(-625 3050);
DISPLAY 0.617021 (-625 3050);
PAINT SKYBLUE (-625 3050);
FORCEADD AGND0..1
(-675 2725);
FORCEPROP 3 LASTPIN (-675 2775) SIG_NAME AGND_HSC\g
J 0
(-665 2785);
DISPLAY 0.659574 (-665 2785);
PAINT MONO (-665 2785);
DISPLAY INVISIBLE (-665 2785);
FORCEPROP 1 LAST VOLTAGE 0
J 0
(-675 2725);
PAINT SKYBLUE (-675 2725);
DISPLAY INVISIBLE (-675 2725);
FORCEPROP 2 LAST CDS_LIB mstr_symbols
J 0
(-675 2725);
PAINT ORANGE (-675 2725);
DISPLAY INVISIBLE (-675 2725);
FORCEPROP 2 LAST BOM_COST MIO_VRD_MAIN
J 0
(-650 2700);
PAINT ORANGE (-650 2700);
DISPLAY INVISIBLE (-650 2700);
FORCEPROP 1 LAST PATH I41
J 0
(-600 2725);
DISPLAY 0.872340 (-600 2725);
PAINT AQUA (-600 2725);
DISPLAY INVISIBLE (-600 2725);
FORCEPROP 2 LAST ROOM VR_P3V3
J 0
(-700 2700);
PAINT ORANGE (-700 2700);
DISPLAY INVISIBLE (-700 2700);
FORCEPROP 1 LAST BODY_TYPE PLUMBING
J 0
(-720 2682);
DISPLAY 0.340426 (-720 2682);
PAINT GREEN (-720 2682);
DISPLAY INVISIBLE (-720 2682);
FORCEPROP 1 LAST HDL_POWER AGND_HSC
J 1
(-675 2675);
DISPLAY 0.617021 (-675 2675);
PAINT GREEN (-675 2675);
FORCEADD CAP_A..1
(-175 3425);
FORCEPROP 2 LAST CDS_SEC 1
J 0
(-125 3625);
DISPLAY 1.021277 (-125 3625);
PAINT ORANGE (-125 3625);
DISPLAY INVISIBLE (-125 3625);
FORCEPROP 0 LAST ROOM HOT_SWAP
J 2
(-125 3575);
DISPLAY 1.021277 (-125 3575);
PAINT ORANGE (-125 3575);
DISPLAY INVISIBLE (-125 3575);
FORCEPROP 1 LAST PATH I42
J 0
(-125 3575);
DISPLAY 0.978723 (-125 3575);
PAINT WHITE (-125 3575);
DISPLAY INVISIBLE (-125 3575);
FORCEPROP 2 LAST CDS_LOCATION C1D22
J 0
(-125 3525);
DISPLAY 0.617021 (-125 3525);
PAINT AQUA (-125 3525);
DISPLAY INVISIBLE (-125 3525);
FORCEPROP 1 LASTPIN (-175 3525) $PN 1
J 0
(-165 3505);
DISPLAY 0.787234 (-165 3505);
PAINT ORANGE (-165 3505);
DISPLAY INVISIBLE (-165 3505);
FORCEPROP 2 LAST CDS_LIB dev_discrete
J 0
(-175 3425);
PAINT ORANGE (-175 3425);
DISPLAY INVISIBLE (-175 3425);
FORCEPROP 1 LASTPIN (-175 3325) $PN 2
J 0
(-165 3305);
DISPLAY 0.787234 (-165 3305);
PAINT ORANGE (-165 3305);
DISPLAY INVISIBLE (-165 3305);
FORCEPROP 1 LAST MATERIAL EMPTY
J 0
(-125 3325);
DISPLAY 0.617021 (-125 3325);
PAINT RED (-125 3325);
FORCEPROP 1 LAST LOCATION C1D22
J 0
(-125 3525);
DISPLAY 0.617021 (-125 3525);
PAINT AQUA (-125 3525);
FORCEPROP 1 LAST PART_NUMBER A36096-030
J 0
(-125 3275);
DISPLAY 0.617021 (-125 3275);
PAINT BLUE (-125 3275);
FORCEPROP 1 LAST VALUE 0.1UF
J 0
(-125 3475);
DISPLAY 0.617021 (-125 3475);
PAINT SKYBLUE (-125 3475);
FORCEPROP 1 LAST PACK_TYPE 0402V
J 0
(-125 3225);
DISPLAY 0.617021 (-125 3225);
PAINT SKYBLUE (-125 3225);
FORCEPROP 1 LAST TOLERANCE 10%
J 0
(-125 3375);
DISPLAY 0.617021 (-125 3375);
PAINT SKYBLUE (-125 3375);
FORCEPROP 1 LAST VOLTAGE 16V
J 0
(-125 3425);
DISPLAY 0.617021 (-125 3425);
PAINT SKYBLUE (-125 3425);
FORCEADD RES..1
(250 3625);
FORCEPROP 1 LASTPIN (350 3625) $PN 2
J 0
(312 3637);
DISPLAY 0.787234 (312 3637);
PAINT ORANGE (312 3637);
DISPLAY INVISIBLE (312 3637);
FORCEPROP 2 LAST $SEC 1
J 0
(200 3825);
DISPLAY 0.680851 (200 3825);
PAINT MONO (200 3825);
DISPLAY INVISIBLE (200 3825);
FORCEPROP 2 LAST CDS_SEC 1
J 0
(200 3825);
DISPLAY 1.021277 (200 3825);
PAINT ORANGE (200 3825);
DISPLAY INVISIBLE (200 3825);
FORCEPROP 2 LAST CDS_LIB mstr_discrete
J 0
(250 3625);
PAINT ORANGE (250 3625);
DISPLAY INVISIBLE (250 3625);
FORCEPROP 2 LAST CDS_LOCATION R1D45
J 0
(200 3675);
DISPLAY 0.617021 (200 3675);
PAINT AQUA (200 3675);
DISPLAY INVISIBLE (200 3675);
FORCEPROP 1 LAST PATH I43
J 0
(200 3775);
DISPLAY 0.978723 (200 3775);
PAINT WHITE (200 3775);
DISPLAY INVISIBLE (200 3775);
FORCEPROP 0 LAST ROOM HOT_SWAP
J 0
(200 3775);
DISPLAY 1.021277 (200 3775);
PAINT ORANGE (200 3775);
DISPLAY INVISIBLE (200 3775);
FORCEPROP 1 LASTPIN (150 3625) $PN 1
J 0
(162 3637);
DISPLAY 0.787234 (162 3637);
PAINT ORANGE (162 3637);
DISPLAY INVISIBLE (162 3637);
FORCEPROP 1 LAST PACK_TYPE 0402
J 0
(450 3550);
DISPLAY 0.617021 (450 3550);
PAINT SKYBLUE (450 3550);
FORCEPROP 1 LAST LOCATION R1D45
J 0
(200 3675);
DISPLAY 0.617021 (200 3675);
PAINT AQUA (200 3675);
FORCEPROP 1 LAST TOLERANCE 5%
J 0
(375 3550);
DISPLAY 0.617021 (375 3550);
PAINT SKYBLUE (375 3550);
FORCEPROP 1 LAST PART_NUMBER G21497-005
J 0
(150 3475);
DISPLAY 0.617021 (150 3475);
PAINT BLUE (150 3475);
FORCEPROP 1 LAST MATERIAL CHIP
J 0
(250 3525);
DISPLAY 0.617021 (250 3525);
PAINT SKYBLUE (250 3525);
FORCEPROP 1 LAST VALUE 0.0
J 2
(225 3525);
DISPLAY 0.617021 (225 3525);
PAINT SKYBLUE (225 3525);
FORCEPROP 1 LAST WATTAGE 1/16W
J 2
(175 3550);
DISPLAY 0.617021 (175 3550);
PAINT SKYBLUE (175 3550);
FORCEADD RES..1
(225 3150);
FORCEPROP 1 LASTPIN (325 3150) $PN 2
J 0
(287 3162);
DISPLAY 0.787234 (287 3162);
PAINT ORANGE (287 3162);
DISPLAY INVISIBLE (287 3162);
FORCEPROP 2 LAST CDS_SEC 1
J 0
(175 3350);
DISPLAY 1.021277 (175 3350);
PAINT ORANGE (175 3350);
DISPLAY INVISIBLE (175 3350);
FORCEPROP 2 LAST $SEC 1
J 0
(175 3350);
DISPLAY 0.680851 (175 3350);
PAINT MONO (175 3350);
DISPLAY INVISIBLE (175 3350);
FORCEPROP 0 LAST ROOM HOT_SWAP
J 0
(175 3300);
DISPLAY 1.021277 (175 3300);
PAINT ORANGE (175 3300);
DISPLAY INVISIBLE (175 3300);
FORCEPROP 1 LAST PATH I44
J 0
(175 3300);
DISPLAY 0.978723 (175 3300);
PAINT WHITE (175 3300);
DISPLAY INVISIBLE (175 3300);
FORCEPROP 1 LASTPIN (125 3150) $PN 1
J 0
(137 3162);
DISPLAY 0.787234 (137 3162);
PAINT ORANGE (137 3162);
DISPLAY INVISIBLE (137 3162);
FORCEPROP 2 LAST CDS_LOCATION R1D44
J 0
(175 3200);
DISPLAY 0.617021 (175 3200);
PAINT AQUA (175 3200);
DISPLAY INVISIBLE (175 3200);
FORCEPROP 2 LAST CDS_LIB mstr_discrete
J 0
(225 3150);
PAINT ORANGE (225 3150);
DISPLAY INVISIBLE (225 3150);
FORCEPROP 1 LAST PACK_TYPE 0402
J 0
(425 3075);
DISPLAY 0.617021 (425 3075);
PAINT SKYBLUE (425 3075);
FORCEPROP 1 LAST TOLERANCE 5%
J 0
(350 3075);
DISPLAY 0.617021 (350 3075);
PAINT SKYBLUE (350 3075);
FORCEPROP 1 LAST LOCATION R1D44
J 0
(175 3200);
DISPLAY 0.617021 (175 3200);
PAINT AQUA (175 3200);
FORCEPROP 1 LAST WATTAGE 1/16W
J 2
(150 3075);
DISPLAY 0.617021 (150 3075);
PAINT SKYBLUE (150 3075);
FORCEPROP 1 LAST VALUE 0.0
J 2
(200 3050);
DISPLAY 0.617021 (200 3050);
PAINT SKYBLUE (200 3050);
FORCEPROP 1 LAST MATERIAL CHIP
J 0
(225 3050);
DISPLAY 0.617021 (225 3050);
PAINT SKYBLUE (225 3050);
FORCEPROP 1 LAST PART_NUMBER G21497-005
J 0
(125 3000);
DISPLAY 0.617021 (125 3000);
PAINT BLUE (125 3000);
FORCEADD OFFPAGE..4
R 2
(325 2350);
FORCEPROP 2 LAST PATH I45
J 0
(375 2425);
DISPLAY 1.021277 (375 2425);
PAINT ORANGE (375 2425);
DISPLAY INVISIBLE (375 2425);
FORCEPROP 2 LAST CDS_LIB mstr_standard
J 0
(325 2350);
PAINT ORANGE (325 2350);
DISPLAY INVISIBLE (325 2350);
FORCEPROP 1 LAST OFFPAGE TRUE
J 2
(0 2225);
PAINT GREEN (0 2225);
DISPLAY INVISIBLE (0 2225);
FORCEPROP 1 LAST COMMENT_BODY TRUE
J 2
(350 2250);
DISPLAY 1.872340 (350 2250);
PAINT GREEN (350 2250);
DISPLAY INVISIBLE (350 2250);
FORCEPROP 2 LAST $XR0 199 
J 0
(43 2350);
DISPLAY 0.638298 (43 2350);
PAINT MONO (43 2350);
FORCEADD OFFPAGE..4
R 2
(325 2250);
FORCEPROP 2 LAST PATH I46
J 0
(375 2325);
DISPLAY 1.021277 (375 2325);
PAINT ORANGE (375 2325);
DISPLAY INVISIBLE (375 2325);
FORCEPROP 2 LAST CDS_LIB mstr_standard
J 0
(325 2250);
PAINT ORANGE (325 2250);
DISPLAY INVISIBLE (325 2250);
FORCEPROP 1 LAST OFFPAGE TRUE
J 2
(0 2125);
PAINT GREEN (0 2125);
DISPLAY INVISIBLE (0 2125);
FORCEPROP 1 LAST COMMENT_BODY TRUE
J 2
(350 2150);
DISPLAY 1.872340 (350 2150);
PAINT GREEN (350 2150);
DISPLAY INVISIBLE (350 2150);
FORCEPROP 2 LAST $XR0 199 
J 0
(43 2250);
DISPLAY 0.638298 (43 2250);
PAINT MONO (43 2250);
FORCEADD RES..2
(875 2800);
FORCEPROP 0 LAST ROOM HOT_SWAP
J 0
(925 3025);
DISPLAY 1.021277 (925 3025);
PAINT ORANGE (925 3025);
DISPLAY INVISIBLE (925 3025);
FORCEPROP 1 LASTPIN (875 2900) $PN 1
J 0
(880 2862);
DISPLAY 0.787234 (880 2862);
PAINT ORANGE (880 2862);
DISPLAY INVISIBLE (880 2862);
FORCEPROP 2 LAST CDS_LOCATION R9P27
J 0
(920 2925);
DISPLAY 0.617021 (920 2925);
PAINT AQUA (920 2925);
DISPLAY INVISIBLE (920 2925);
FORCEPROP 1 LAST PATH I47
J 0
(925 2975);
DISPLAY 0.978723 (925 2975);
PAINT WHITE (925 2975);
DISPLAY INVISIBLE (925 2975);
FORCEPROP 2 LAST $SEC 1
J 0
(925 3025);
DISPLAY 0.680851 (925 3025);
PAINT MONO (925 3025);
DISPLAY INVISIBLE (925 3025);
FORCEPROP 2 LAST CDS_SEC 1
J 0
(925 3025);
DISPLAY 1.021277 (925 3025);
PAINT ORANGE (925 3025);
DISPLAY INVISIBLE (925 3025);
FORCEPROP 2 LAST CDS_LIB mstr_discrete
J 0
(875 2800);
PAINT ORANGE (875 2800);
DISPLAY INVISIBLE (875 2800);
FORCEPROP 1 LASTPIN (875 2700) $PN 2
J 0
(880 2710);
DISPLAY 0.787234 (880 2710);
PAINT ORANGE (880 2710);
DISPLAY INVISIBLE (880 2710);
FORCEPROP 1 LAST LOCATION R9P27
J 0
(920 2925);
DISPLAY 0.617021 (920 2925);
PAINT AQUA (920 2925);
FORCEPROP 1 LAST VALUE 10.0
J 0
(920 2875);
DISPLAY 0.617021 (920 2875);
PAINT SKYBLUE (920 2875);
FORCEPROP 1 LAST MATERIAL CHIP
J 0
(915 2725);
DISPLAY 0.617021 (915 2725);
PAINT SKYBLUE (915 2725);
FORCEPROP 1 LAST TOLERANCE 1%
J 0
(920 2825);
DISPLAY 0.617021 (920 2825);
PAINT SKYBLUE (920 2825);
FORCEPROP 1 LAST PART_NUMBER G21796-066
J 0
(915 2675);
DISPLAY 0.617021 (915 2675);
PAINT BLUE (915 2675);
FORCEPROP 1 LAST PACK_TYPE 0402
J 0
(915 2625);
DISPLAY 0.617021 (915 2625);
PAINT SKYBLUE (915 2625);
FORCEPROP 1 LAST WATTAGE 1/16W
J 0
(915 2775);
DISPLAY 0.617021 (915 2775);
PAINT SKYBLUE (915 2775);
FORCEADD RES..2
R 2
(750 2800);
FORCEPROP 2 LAST $SEC 1
J 0
(700 3025);
DISPLAY 0.680851 (700 3025);
PAINT MONO (700 3025);
DISPLAY INVISIBLE (700 3025);
FORCEPROP 2 LAST CDS_SEC 1
J 0
(700 3025);
DISPLAY 1.021277 (700 3025);
PAINT ORANGE (700 3025);
DISPLAY INVISIBLE (700 3025);
FORCEPROP 2 LAST CDS_LOCATION R1D46
J 2
(705 2925);
DISPLAY 0.617021 (705 2925);
PAINT AQUA (705 2925);
DISPLAY INVISIBLE (705 2925);
FORCEPROP 1 LAST PATH I48
J 2
(700 2975);
DISPLAY 0.978723 (700 2975);
PAINT WHITE (700 2975);
DISPLAY INVISIBLE (700 2975);
FORCEPROP 0 LAST ROOM HOT_SWAP
J 2
(700 3025);
DISPLAY 0.808511 (700 3025);
PAINT ORANGE (700 3025);
DISPLAY INVISIBLE (700 3025);
FORCEPROP 1 LASTPIN (750 2900) $PN 1
J 2
(745 2862);
DISPLAY 0.787234 (745 2862);
PAINT ORANGE (745 2862);
DISPLAY INVISIBLE (745 2862);
FORCEPROP 2 LAST CDS_LIB mstr_discrete
J 2
(750 2800);
PAINT ORANGE (750 2800);
DISPLAY INVISIBLE (750 2800);
FORCEPROP 1 LASTPIN (750 2700) $PN 2
J 2
(745 2710);
DISPLAY 0.787234 (745 2710);
PAINT ORANGE (745 2710);
DISPLAY INVISIBLE (745 2710);
FORCEPROP 1 LAST VALUE 10.0
J 2
(705 2875);
DISPLAY 0.617021 (705 2875);
PAINT SKYBLUE (705 2875);
FORCEPROP 1 LAST LOCATION R1D46
J 2
(705 2925);
DISPLAY 0.617021 (705 2925);
PAINT AQUA (705 2925);
FORCEPROP 1 LAST TOLERANCE 1%
J 2
(705 2825);
DISPLAY 0.617021 (705 2825);
PAINT SKYBLUE (705 2825);
FORCEPROP 1 LAST WATTAGE 1/16W
J 2
(710 2775);
DISPLAY 0.617021 (710 2775);
PAINT SKYBLUE (710 2775);
FORCEPROP 1 LAST MATERIAL CHIP
J 2
(710 2725);
DISPLAY 0.617021 (710 2725);
PAINT SKYBLUE (710 2725);
FORCEPROP 1 LAST PART_NUMBER G21796-066
J 2
(710 2675);
DISPLAY 0.617021 (710 2675);
PAINT BLUE (710 2675);
FORCEPROP 1 LAST PACK_TYPE 0402
J 2
(710 2625);
DISPLAY 0.617021 (710 2625);
PAINT SKYBLUE (710 2625);
FORCEADD RES_PWR..2
(1125 3200);
FORCEPROP 2 LAST SEC_TYPE 6PAD
J 0
(1075 3425);
DISPLAY 1.021277 (1075 3425);
PAINT ORANGE (1075 3425);
DISPLAY INVISIBLE (1075 3425);
FORCEPROP 2 LAST SEC 1
J 0
(1075 3425);
DISPLAY 0.680851 (1075 3425);
PAINT MONO (1075 3425);
DISPLAY INVISIBLE (1075 3425);
FORCEPROP 1 LAST PATH I49
J 0
(1075 3380);
DISPLAY 0.617021 (1075 3380);
PAINT GREEN (1075 3380);
DISPLAY INVISIBLE (1075 3380);
FORCEPROP 0 LAST ROOM HOT_SWAP
J 0
(1075 3450);
DISPLAY 1.021277 (1075 3450);
PAINT ORANGE (1075 3450);
DISPLAY INVISIBLE (1075 3450);
FORCEPROP 2 LAST CDS_LOCATION R9R1
J 0
(1075 3325);
DISPLAY 0.617021 (1075 3325);
PAINT AQUA (1075 3325);
DISPLAY INVISIBLE (1075 3325);
FORCEPROP 2 LAST CDS_LIB mstr_discrete
J 0
(1125 3200);
PAINT ORANGE (1125 3200);
DISPLAY INVISIBLE (1125 3200);
FORCEPROP 1 LAST CDS_LMAN_SYM_OUTLINE -50,100,50,-100
J 0
(1125 3200);
DISPLAY 0.468085 (1125 3200);
PAINT GREEN (1125 3200);
DISPLAY INVISIBLE (1125 3200);
FORCEPROP 1 LAST PART_NUMBER E74391-005
J 0
(1075 3355);
DISPLAY 0.617021 (1075 3355);
PAINT BLUE (1075 3355);
FORCEPROP 1 LAST LOCATION R9R1
J 0
(1075 3325);
DISPLAY 0.617021 (1075 3325);
PAINT AQUA (1075 3325);
FORCEPROP 2 LASTPIN (1225 3150) $PN 6
J 0
(1235 3160);
DISPLAY 0.617021 (1235 3160);
PAINT ORANGE (1235 3160);
FORCEPROP 2 LASTPIN (1225 3200) $PN 4
J 0
(1235 3210);
DISPLAY 0.617021 (1235 3210);
PAINT ORANGE (1235 3210);
FORCEPROP 2 LASTPIN (1225 3250) $PN 2
J 0
(1235 3260);
DISPLAY 0.617021 (1235 3260);
PAINT ORANGE (1235 3260);
FORCEPROP 1 LAST MATERIAL CHIP
J 0
(1175 3025);
DISPLAY 0.617021 (1175 3025);
PAINT SKYBLUE (1175 3025);
FORCEPROP 1 LAST PACK_TYPE 6PAD
J 0
(1075 2975);
DISPLAY 0.617021 (1075 2975);
PAINT SKYBLUE (1075 2975);
FORCEPROP 1 LAST WATTAGE 3W
J 0
(1050 3025);
DISPLAY 0.617021 (1050 3025);
PAINT SKYBLUE (1050 3025);
FORCEPROP 1 LAST VALUE 0.001
J 2
(1075 3050);
DISPLAY 0.617021 (1075 3050);
PAINT SKYBLUE (1075 3050);
FORCEPROP 2 LASTPIN (1025 3150) $PN 5
J 2
(1015 3160);
DISPLAY 0.617021 (1015 3160);
PAINT ORANGE (1015 3160);
FORCEPROP 2 LASTPIN (1025 3200) $PN 3
J 2
(1015 3210);
DISPLAY 0.617021 (1015 3210);
PAINT ORANGE (1015 3210);
FORCEPROP 2 LASTPIN (1025 3250) $PN 1
J 2
(1015 3260);
DISPLAY 0.617021 (1015 3260);
PAINT ORANGE (1015 3260);
FORCEPROP 1 LAST TOLERANCE 1%
J 0
(1175 3050);
DISPLAY 0.617021 (1175 3050);
PAINT SKYBLUE (1175 3050);
FORCEADD RES_PWR..2
(1125 3600);
FORCEPROP 0 LAST ROOM HOT_SWAP
J 0
(1075 3850);
DISPLAY 1.021277 (1075 3850);
PAINT ORANGE (1075 3850);
DISPLAY INVISIBLE (1075 3850);
FORCEPROP 2 LAST SEC 1
J 0
(1075 3825);
DISPLAY 0.680851 (1075 3825);
PAINT MONO (1075 3825);
DISPLAY INVISIBLE (1075 3825);
FORCEPROP 2 LAST SEC_TYPE 6PAD
J 0
(1075 3825);
DISPLAY 1.021277 (1075 3825);
PAINT ORANGE (1075 3825);
DISPLAY INVISIBLE (1075 3825);
FORCEPROP 2 LAST CDS_LOCATION R1D49
J 0
(1075 3725);
DISPLAY 0.617021 (1075 3725);
PAINT AQUA (1075 3725);
DISPLAY INVISIBLE (1075 3725);
FORCEPROP 1 LAST PATH I50
J 0
(1075 3780);
DISPLAY 0.617021 (1075 3780);
PAINT GREEN (1075 3780);
DISPLAY INVISIBLE (1075 3780);
FORCEPROP 1 LAST CDS_LMAN_SYM_OUTLINE -50,100,50,-100
J 0
(1125 3600);
DISPLAY 0.468085 (1125 3600);
PAINT GREEN (1125 3600);
DISPLAY INVISIBLE (1125 3600);
FORCEPROP 2 LAST CDS_LIB mstr_discrete
J 0
(1125 3600);
PAINT ORANGE (1125 3600);
DISPLAY INVISIBLE (1125 3600);
FORCEPROP 1 LAST PART_NUMBER E74391-005
J 0
(1075 3755);
DISPLAY 0.617021 (1075 3755);
PAINT BLUE (1075 3755);
FORCEPROP 2 LASTPIN (1225 3650) $PN 2
J 0
(1235 3660);
DISPLAY 0.617021 (1235 3660);
PAINT ORANGE (1235 3660);
FORCEPROP 2 LASTPIN (1225 3600) $PN 4
J 0
(1235 3610);
DISPLAY 0.617021 (1235 3610);
PAINT ORANGE (1235 3610);
FORCEPROP 1 LAST LOCATION R1D49
J 0
(1075 3725);
DISPLAY 0.617021 (1075 3725);
PAINT AQUA (1075 3725);
FORCEPROP 2 LASTPIN (1225 3550) $PN 6
J 0
(1235 3560);
DISPLAY 0.617021 (1235 3560);
PAINT ORANGE (1235 3560);
FORCEPROP 1 LAST MATERIAL CHIP
J 0
(1175 3425);
DISPLAY 0.617021 (1175 3425);
PAINT SKYBLUE (1175 3425);
FORCEPROP 1 LAST TOLERANCE 1%
J 0
(1175 3450);
DISPLAY 0.617021 (1175 3450);
PAINT SKYBLUE (1175 3450);
FORCEPROP 1 LAST PACK_TYPE 6PAD
J 0
(1075 3400);
DISPLAY 0.617021 (1075 3400);
PAINT SKYBLUE (1075 3400);
FORCEPROP 1 LAST WATTAGE 3W
J 0
(1050 3425);
DISPLAY 0.617021 (1050 3425);
PAINT SKYBLUE (1050 3425);
FORCEPROP 1 LAST VALUE 0.001
J 2
(1075 3450);
DISPLAY 0.617021 (1075 3450);
PAINT SKYBLUE (1075 3450);
FORCEPROP 2 LASTPIN (1025 3650) $PN 1
J 2
(1015 3660);
DISPLAY 0.617021 (1015 3660);
PAINT ORANGE (1015 3660);
FORCEPROP 2 LASTPIN (1025 3600) $PN 3
J 2
(1015 3610);
DISPLAY 0.617021 (1015 3610);
PAINT ORANGE (1015 3610);
FORCEPROP 2 LASTPIN (1025 3550) $PN 5
J 2
(1015 3560);
DISPLAY 0.617021 (1015 3560);
PAINT ORANGE (1015 3560);
FORCEADD RES..2
R 2
(1350 2800);
FORCEPROP 2 LAST CDS_SEC 1
J 0
(1300 3025);
DISPLAY 1.021277 (1300 3025);
PAINT ORANGE (1300 3025);
DISPLAY INVISIBLE (1300 3025);
FORCEPROP 2 LAST $SEC 1
J 0
(1300 3025);
DISPLAY 0.680851 (1300 3025);
PAINT MONO (1300 3025);
DISPLAY INVISIBLE (1300 3025);
FORCEPROP 2 LAST CDS_LOCATION R9P26
J 2
(1305 2925);
DISPLAY 0.617021 (1305 2925);
PAINT AQUA (1305 2925);
DISPLAY INVISIBLE (1305 2925);
FORCEPROP 1 LAST PATH I51
J 2
(1300 2975);
DISPLAY 0.978723 (1300 2975);
PAINT WHITE (1300 2975);
DISPLAY INVISIBLE (1300 2975);
FORCEPROP 0 LAST ROOM HOT_SWAP
J 2
(1300 3025);
DISPLAY 1.021277 (1300 3025);
PAINT ORANGE (1300 3025);
DISPLAY INVISIBLE (1300 3025);
FORCEPROP 1 LASTPIN (1350 2900) $PN 1
J 2
(1345 2862);
DISPLAY 0.787234 (1345 2862);
PAINT ORANGE (1345 2862);
DISPLAY INVISIBLE (1345 2862);
FORCEPROP 2 LAST CDS_LIB mstr_discrete
J 2
(1350 2800);
PAINT ORANGE (1350 2800);
DISPLAY INVISIBLE (1350 2800);
FORCEPROP 1 LASTPIN (1350 2700) $PN 2
J 2
(1345 2710);
DISPLAY 0.787234 (1345 2710);
PAINT ORANGE (1345 2710);
DISPLAY INVISIBLE (1345 2710);
FORCEPROP 1 LAST TOLERANCE 1%
J 2
(1305 2825);
DISPLAY 0.617021 (1305 2825);
PAINT SKYBLUE (1305 2825);
FORCEPROP 1 LAST PACK_TYPE 0402
J 2
(1310 2625);
DISPLAY 0.617021 (1310 2625);
PAINT SKYBLUE (1310 2625);
FORCEPROP 1 LAST MATERIAL CHIP
J 2
(1310 2725);
DISPLAY 0.617021 (1310 2725);
PAINT SKYBLUE (1310 2725);
FORCEPROP 1 LAST PART_NUMBER G21796-066
J 2
(1310 2675);
DISPLAY 0.617021 (1310 2675);
PAINT BLUE (1310 2675);
FORCEPROP 1 LAST VALUE 10.0
J 2
(1305 2875);
DISPLAY 0.617021 (1305 2875);
PAINT SKYBLUE (1305 2875);
FORCEPROP 1 LAST WATTAGE 1/16W
J 2
(1310 2775);
DISPLAY 0.617021 (1310 2775);
PAINT SKYBLUE (1310 2775);
FORCEPROP 1 LAST LOCATION R9P26
J 2
(1305 2925);
DISPLAY 0.617021 (1305 2925);
PAINT AQUA (1305 2925);
FORCEADD RES..2
(1475 2800);
FORCEPROP 1 LASTPIN (1475 2900) $PN 1
J 0
(1480 2862);
DISPLAY 0.787234 (1480 2862);
PAINT ORANGE (1480 2862);
DISPLAY INVISIBLE (1480 2862);
FORCEPROP 0 LAST ROOM HOT_SWAP
J 0
(1525 3025);
DISPLAY 1.021277 (1525 3025);
PAINT ORANGE (1525 3025);
DISPLAY INVISIBLE (1525 3025);
FORCEPROP 1 LAST PATH I52
J 0
(1525 2975);
DISPLAY 0.978723 (1525 2975);
PAINT WHITE (1525 2975);
DISPLAY INVISIBLE (1525 2975);
FORCEPROP 2 LAST CDS_LOCATION R1D47
J 0
(1520 2925);
DISPLAY 0.617021 (1520 2925);
PAINT AQUA (1520 2925);
DISPLAY INVISIBLE (1520 2925);
FORCEPROP 2 LAST $SEC 1
J 0
(1525 3025);
DISPLAY 0.680851 (1525 3025);
PAINT MONO (1525 3025);
DISPLAY INVISIBLE (1525 3025);
FORCEPROP 2 LAST CDS_SEC 1
J 0
(1525 3025);
DISPLAY 1.021277 (1525 3025);
PAINT ORANGE (1525 3025);
DISPLAY INVISIBLE (1525 3025);
FORCEPROP 2 LAST CDS_LIB mstr_discrete
J 0
(1475 2800);
PAINT ORANGE (1475 2800);
DISPLAY INVISIBLE (1475 2800);
FORCEPROP 1 LASTPIN (1475 2700) $PN 2
J 0
(1480 2710);
DISPLAY 0.787234 (1480 2710);
PAINT ORANGE (1480 2710);
DISPLAY INVISIBLE (1480 2710);
FORCEPROP 1 LAST LOCATION R1D47
J 0
(1520 2925);
DISPLAY 0.617021 (1520 2925);
PAINT AQUA (1520 2925);
FORCEPROP 1 LAST PART_NUMBER G21796-066
J 0
(1515 2675);
DISPLAY 0.617021 (1515 2675);
PAINT BLUE (1515 2675);
FORCEPROP 1 LAST VALUE 10.0
J 0
(1520 2875);
DISPLAY 0.617021 (1520 2875);
PAINT SKYBLUE (1520 2875);
FORCEPROP 1 LAST TOLERANCE 1%
J 0
(1520 2825);
DISPLAY 0.617021 (1520 2825);
PAINT SKYBLUE (1520 2825);
FORCEPROP 1 LAST PACK_TYPE 0402
J 0
(1515 2625);
DISPLAY 0.617021 (1515 2625);
PAINT SKYBLUE (1515 2625);
FORCEPROP 1 LAST MATERIAL CHIP
J 0
(1515 2725);
DISPLAY 0.617021 (1515 2725);
PAINT SKYBLUE (1515 2725);
FORCEPROP 1 LAST WATTAGE 1/16W
J 0
(1515 2775);
DISPLAY 0.617021 (1515 2775);
PAINT SKYBLUE (1515 2775);
FORCEADD P12V_PSU..1
(900 3825);
FORCEPROP 3 LASTPIN (900 3775) SIG_NAME P12V_PSU\g
J 0
(910 3785);
DISPLAY 0.659574 (910 3785);
PAINT MONO (910 3785);
DISPLAY INVISIBLE (910 3785);
FORCEPROP 2 LAST ROOM P2V5_LAN_AUX_VR
J 0
(900 3925);
DISPLAY 0.617021 (900 3925);
PAINT ORANGE (900 3925);
DISPLAY INVISIBLE (900 3925);
FORCEPROP 1 LAST PATH I53
J 0
(950 3850);
DISPLAY 0.872340 (950 3850);
PAINT AQUA (950 3850);
DISPLAY INVISIBLE (950 3850);
FORCEPROP 2 LAST BOM_COST NT_BASE_VRD
J 0
(900 3925);
DISPLAY 0.617021 (900 3925);
PAINT ORANGE (900 3925);
DISPLAY INVISIBLE (900 3925);
FORCEPROP 2 LAST CDS_LIB mstr_symbols
J 0
(900 3825);
PAINT ORANGE (900 3825);
DISPLAY INVISIBLE (900 3825);
FORCEPROP 1 LAST VOLTAGE 12.0
J 0
(855 3782);
DISPLAY 0.340426 (855 3782);
PAINT SKYBLUE (855 3782);
DISPLAY INVISIBLE (855 3782);
FORCEPROP 1 LAST BODY_TYPE PLUMBING
J 0
(855 3782);
DISPLAY 0.340426 (855 3782);
PAINT GREEN (855 3782);
DISPLAY INVISIBLE (855 3782);
FORCEPROP 1 LAST HDL_POWER P12V_PSU
J 1
(900 3875);
DISPLAY 0.872340 (900 3875);
PAINT GREEN (900 3875);
DISPLAY INVISIBLE (900 3875);
FORCEADD MOSFETN_1D3S..1
R 1
(2275 3375);
FORCEPROP 2 LAST SEC 1
J 0
(2425 3525);
DISPLAY 0.680851 (2425 3525);
PAINT MONO (2425 3525);
DISPLAY INVISIBLE (2425 3525);
FORCEPROP 2 LAST SEC_TYPE SOT5
J 0
(2425 3525);
DISPLAY 1.021277 (2425 3525);
PAINT ORANGE (2425 3525);
DISPLAY INVISIBLE (2425 3525);
FORCEPROP 1 LAST PACK_TYPE SOT5
R 1
J 0
(2375 3525);
DISPLAY 0.957447 (2375 3525);
PAINT SKYBLUE (2375 3525);
DISPLAY INVISIBLE (2375 3525);
FORCEPROP 2 LAST CDS_LIB mstr_discrete
R 1
J 0
(2275 3375);
PAINT ORANGE (2275 3375);
DISPLAY INVISIBLE (2275 3375);
FORCEPROP 2 LAST CDS_LOCATION EU1E3
R 1
J 0
(2225 3525);
DISPLAY 0.617021 (2225 3525);
PAINT AQUA (2225 3525);
DISPLAY INVISIBLE (2225 3525);
FORCEPROP 1 LAST PATH I54
R 1
J 0
(2175 3525);
DISPLAY 0.978723 (2175 3525);
PAINT WHITE (2175 3525);
DISPLAY INVISIBLE (2175 3525);
FORCEPROP 0 LAST ROOM HOT_SWAP
R 1
J 0
(2125 3525);
DISPLAY 1.021277 (2125 3525);
PAINT ORANGE (2125 3525);
DISPLAY INVISIBLE (2125 3525);
FORCEPROP 1 LAST LOCATION EU1E3
R 1
J 0
(2225 3525);
DISPLAY 0.617021 (2225 3525);
PAINT AQUA (2225 3525);
FORCEPROP 2 LASTPIN (2425 3425) $PN 3
J 0
(2435 3435);
DISPLAY 0.617021 (2435 3435);
PAINT ORANGE (2435 3435);
FORCEPROP 2 LASTPIN (2425 3325) $PN 1
J 0
(2435 3335);
DISPLAY 0.617021 (2435 3335);
PAINT ORANGE (2435 3335);
FORCEPROP 2 LASTPIN (2425 3375) $PN 2
J 0
(2435 3385);
DISPLAY 0.617021 (2435 3385);
PAINT ORANGE (2435 3385);
FORCEPROP 2 LASTPIN (2325 3175) $PN 4
R 1
J 2
(2315 3165);
DISPLAY 0.617021 (2315 3165);
PAINT ORANGE (2315 3165);
FORCEPROP 1 LAST MATERIAL IC
R 1
J 0
(2275 3525);
DISPLAY 0.617021 (2275 3525);
PAINT SKYBLUE (2275 3525);
FORCEPROP 2 LASTPIN (2125 3325) $PN 5
J 2
(2115 3335);
DISPLAY 0.617021 (2115 3335);
PAINT ORANGE (2115 3335);
FORCEPROP 1 LAST PART_NUMBER G68777-001
J 0
(2325 3525);
DISPLAY 0.617021 (2325 3525);
PAINT BLUE (2325 3525);
FORCEADD OFFPAGE..4
R 2
(1400 2100);
FORCEPROP 2 LAST PATH I55
J 0
(1450 2175);
DISPLAY 1.021277 (1450 2175);
PAINT ORANGE (1450 2175);
DISPLAY INVISIBLE (1450 2175);
FORCEPROP 2 LAST CDS_LIB mstr_standard
J 0
(1400 2100);
PAINT ORANGE (1400 2100);
DISPLAY INVISIBLE (1400 2100);
FORCEPROP 1 LAST OFFPAGE TRUE
J 2
(1075 1975);
PAINT GREEN (1075 1975);
DISPLAY INVISIBLE (1075 1975);
FORCEPROP 1 LAST COMMENT_BODY TRUE
J 2
(1425 2000);
DISPLAY 1.872340 (1425 2000);
PAINT GREEN (1425 2000);
DISPLAY INVISIBLE (1425 2000);
FORCEPROP 2 LAST $XR0 199 
J 0
(1148 2100);
DISPLAY 0.638298 (1148 2100);
PAINT MONO (1148 2100);
FORCEADD RES..1
(2000 3075);
FORCEPROP 2 LAST CDS_LIB mstr_discrete
J 0
(2000 3075);
PAINT ORANGE (2000 3075);
DISPLAY INVISIBLE (2000 3075);
FORCEPROP 2 LAST SEC_TYPE 0402
J 0
(1950 3275);
DISPLAY 1.021277 (1950 3275);
PAINT ORANGE (1950 3275);
DISPLAY INVISIBLE (1950 3275);
FORCEPROP 2 LAST SEC 1
J 0
(1950 3275);
DISPLAY 0.680851 (1950 3275);
PAINT MONO (1950 3275);
DISPLAY INVISIBLE (1950 3275);
FORCEPROP 2 LAST CDS_LOCATION R1E1
J 0
(1950 3125);
DISPLAY 0.617021 (1950 3125);
PAINT AQUA (1950 3125);
DISPLAY INVISIBLE (1950 3125);
FORCEPROP 1 LAST PATH I56
J 0
(1950 3225);
DISPLAY 0.978723 (1950 3225);
PAINT WHITE (1950 3225);
DISPLAY INVISIBLE (1950 3225);
FORCEPROP 0 LAST ROOM HOT_SWAP
J 0
(1950 3275);
DISPLAY 1.021277 (1950 3275);
PAINT ORANGE (1950 3275);
DISPLAY INVISIBLE (1950 3275);
FORCEPROP 1 LASTPIN (2100 3075) $PN 2
J 0
(2062 3087);
DISPLAY 0.617021 (2062 3087);
PAINT ORANGE (2062 3087);
FORCEPROP 1 LAST TOLERANCE 1%
J 0
(2075 3025);
DISPLAY 0.617021 (2075 3025);
PAINT SKYBLUE (2075 3025);
FORCEPROP 1 LAST LOCATION R1E1
J 0
(1950 3125);
DISPLAY 0.617021 (1950 3125);
PAINT AQUA (1950 3125);
FORCEPROP 1 LASTPIN (1900 3075) $PN 1
J 0
(1912 3087);
DISPLAY 0.617021 (1912 3087);
PAINT ORANGE (1912 3087);
FORCEPROP 1 LAST VALUE 10.0
J 2
(2025 3025);
DISPLAY 0.617021 (2025 3025);
PAINT SKYBLUE (2025 3025);
FORCEPROP 1 LAST PACK_TYPE 0402
J 0
(1775 3025);
DISPLAY 0.617021 (1775 3025);
PAINT SKYBLUE (1775 3025);
FORCEPROP 1 LAST MATERIAL CHIP
J 0
(1800 2925);
DISPLAY 0.617021 (1800 2925);
PAINT SKYBLUE (1800 2925);
FORCEPROP 1 LAST WATTAGE 1/16W
J 2
(1900 2975);
DISPLAY 0.617021 (1900 2975);
PAINT SKYBLUE (1900 2975);
FORCEPROP 1 LAST PART_NUMBER G21796-066
J 0
(1950 3175);
DISPLAY 0.617021 (1950 3175);
PAINT BLUE (1950 3175);
FORCEADD MOSFETN_1D3S..1
R 1
(2300 2825);
FORCEPROP 2 LAST SEC 1
J 0
(2350 3025);
DISPLAY 0.680851 (2350 3025);
PAINT MONO (2350 3025);
DISPLAY INVISIBLE (2350 3025);
FORCEPROP 2 LAST SEC_TYPE SOT5
J 0
(2350 3025);
DISPLAY 1.021277 (2350 3025);
PAINT ORANGE (2350 3025);
DISPLAY INVISIBLE (2350 3025);
FORCEPROP 1 LAST PACK_TYPE SOT5
R 1
J 0
(2400 2975);
DISPLAY 0.957447 (2400 2975);
PAINT SKYBLUE (2400 2975);
DISPLAY INVISIBLE (2400 2975);
FORCEPROP 0 LAST ROOM HOT_SWAP
R 1
J 0
(2150 2975);
DISPLAY 1.021277 (2150 2975);
PAINT ORANGE (2150 2975);
DISPLAY INVISIBLE (2150 2975);
FORCEPROP 1 LAST PATH I57
R 1
J 0
(2200 2975);
DISPLAY 0.978723 (2200 2975);
PAINT WHITE (2200 2975);
DISPLAY INVISIBLE (2200 2975);
FORCEPROP 2 LAST CDS_LOCATION EU9R1
R 1
J 0
(2250 2975);
DISPLAY 0.617021 (2250 2975);
PAINT AQUA (2250 2975);
DISPLAY INVISIBLE (2250 2975);
FORCEPROP 2 LAST CDS_LIB mstr_discrete
J 0
(2300 2825);
PAINT ORANGE (2300 2825);
DISPLAY INVISIBLE (2300 2825);
FORCEPROP 1 LAST LOCATION EU9R1
R 1
J 0
(2250 2975);
DISPLAY 0.617021 (2250 2975);
PAINT AQUA (2250 2975);
FORCEPROP 1 LAST PART_NUMBER G68777-001
J 0
(2350 2975);
DISPLAY 0.617021 (2350 2975);
PAINT BLUE (2350 2975);
FORCEPROP 2 LASTPIN (2450 2825) $PN 2
J 0
(2460 2835);
DISPLAY 0.617021 (2460 2835);
PAINT ORANGE (2460 2835);
FORCEPROP 2 LASTPIN (2450 2875) $PN 3
J 0
(2460 2885);
DISPLAY 0.617021 (2460 2885);
PAINT ORANGE (2460 2885);
FORCEPROP 2 LASTPIN (2450 2775) $PN 1
J 0
(2460 2785);
DISPLAY 0.617021 (2460 2785);
PAINT ORANGE (2460 2785);
FORCEPROP 2 LASTPIN (2350 2625) $PN 4
R 1
J 2
(2340 2615);
DISPLAY 0.617021 (2340 2615);
PAINT ORANGE (2340 2615);
FORCEPROP 1 LAST MATERIAL IC
R 1
J 0
(2300 2975);
DISPLAY 0.617021 (2300 2975);
PAINT SKYBLUE (2300 2975);
FORCEPROP 2 LASTPIN (2150 2775) $PN 5
J 2
(2140 2785);
DISPLAY 0.617021 (2140 2785);
PAINT ORANGE (2140 2785);
FORCEADD RES..1
(2000 2525);
FORCEPROP 1 LASTPIN (2100 2525) $PN 2
J 0
(2062 2537);
DISPLAY 0.787234 (2062 2537);
PAINT ORANGE (2062 2537);
DISPLAY INVISIBLE (2062 2537);
FORCEPROP 0 LAST ROOM HOT_SWAP
J 0
(1950 2725);
DISPLAY 1.021277 (1950 2725);
PAINT ORANGE (1950 2725);
DISPLAY INVISIBLE (1950 2725);
FORCEPROP 2 LAST $SEC 1
J 0
(1950 2725);
DISPLAY 0.680851 (1950 2725);
PAINT MONO (1950 2725);
DISPLAY INVISIBLE (1950 2725);
FORCEPROP 2 LAST CDS_LOCATION R9R4
J 0
(1950 2575);
DISPLAY 0.617021 (1950 2575);
PAINT AQUA (1950 2575);
DISPLAY INVISIBLE (1950 2575);
FORCEPROP 1 LAST PATH I58
J 0
(1950 2675);
DISPLAY 0.978723 (1950 2675);
PAINT WHITE (1950 2675);
DISPLAY INVISIBLE (1950 2675);
FORCEPROP 2 LAST CDS_SEC 1
J 0
(1950 2725);
DISPLAY 1.021277 (1950 2725);
PAINT ORANGE (1950 2725);
DISPLAY INVISIBLE (1950 2725);
FORCEPROP 2 LAST CDS_LIB mstr_discrete
J 0
(2000 2525);
PAINT ORANGE (2000 2525);
DISPLAY INVISIBLE (2000 2525);
FORCEPROP 1 LASTPIN (1900 2525) $PN 1
J 0
(1912 2537);
DISPLAY 0.787234 (1912 2537);
PAINT ORANGE (1912 2537);
DISPLAY INVISIBLE (1912 2537);
FORCEPROP 1 LAST WATTAGE 1/16W
J 2
(1950 2425);
DISPLAY 0.617021 (1950 2425);
PAINT SKYBLUE (1950 2425);
FORCEPROP 1 LAST PACK_TYPE 0402
J 0
(1825 2475);
DISPLAY 0.617021 (1825 2475);
PAINT SKYBLUE (1825 2475);
FORCEPROP 1 LAST TOLERANCE 1%
J 0
(2075 2475);
DISPLAY 0.617021 (2075 2475);
PAINT SKYBLUE (2075 2475);
FORCEPROP 1 LAST LOCATION R9R4
J 0
(1950 2575);
DISPLAY 0.617021 (1950 2575);
PAINT AQUA (1950 2575);
FORCEPROP 1 LAST PART_NUMBER G21796-066
J 0
(1950 2625);
DISPLAY 0.617021 (1950 2625);
PAINT BLUE (1950 2625);
FORCEPROP 1 LAST VALUE 10.0
J 2
(2025 2475);
DISPLAY 0.617021 (2025 2475);
PAINT SKYBLUE (2025 2475);
FORCEPROP 1 LAST MATERIAL CHIP
J 0
(1825 2375);
DISPLAY 0.617021 (1825 2375);
PAINT SKYBLUE (1825 2375);
FORCEADD MOSFETN_1D3S..1
R 1
(2275 2100);
FORCEPROP 2 LAST SEC 1
J 0
(2325 2300);
DISPLAY 0.680851 (2325 2300);
PAINT MONO (2325 2300);
DISPLAY INVISIBLE (2325 2300);
FORCEPROP 2 LAST SEC_TYPE SOT5
J 0
(2325 2300);
DISPLAY 1.021277 (2325 2300);
PAINT ORANGE (2325 2300);
DISPLAY INVISIBLE (2325 2300);
FORCEPROP 1 LAST PACK_TYPE SOT5
R 1
J 0
(2375 2250);
DISPLAY 0.957447 (2375 2250);
PAINT SKYBLUE (2375 2250);
DISPLAY INVISIBLE (2375 2250);
FORCEPROP 0 LAST ROOM HOT_SWAP
R 1
J 0
(2125 2250);
DISPLAY 1.021277 (2125 2250);
PAINT ORANGE (2125 2250);
DISPLAY INVISIBLE (2125 2250);
FORCEPROP 1 LAST PATH I59
R 1
J 0
(2175 2250);
DISPLAY 0.978723 (2175 2250);
PAINT WHITE (2175 2250);
DISPLAY INVISIBLE (2175 2250);
FORCEPROP 2 LAST CDS_LOCATION EU1E1
R 1
J 0
(2225 2250);
DISPLAY 0.617021 (2225 2250);
PAINT AQUA (2225 2250);
DISPLAY INVISIBLE (2225 2250);
FORCEPROP 2 LAST CDS_LIB mstr_discrete
J 0
(2275 2100);
PAINT ORANGE (2275 2100);
DISPLAY INVISIBLE (2275 2100);
FORCEPROP 1 LAST PART_NUMBER G68777-001
J 0
(2325 2250);
DISPLAY 0.617021 (2325 2250);
PAINT BLUE (2325 2250);
FORCEPROP 1 LAST MATERIAL IC
R 1
J 0
(2275 2250);
DISPLAY 0.617021 (2275 2250);
PAINT SKYBLUE (2275 2250);
FORCEPROP 1 LAST LOCATION EU1E1
R 1
J 0
(2225 2250);
DISPLAY 0.617021 (2225 2250);
PAINT AQUA (2225 2250);
FORCEPROP 2 LASTPIN (2125 2050) $PN 5
J 2
(2115 2060);
DISPLAY 0.617021 (2115 2060);
PAINT ORANGE (2115 2060);
FORCEPROP 2 LASTPIN (2425 2150) $PN 3
J 0
(2435 2160);
DISPLAY 0.617021 (2435 2160);
PAINT ORANGE (2435 2160);
FORCEPROP 2 LASTPIN (2425 2050) $PN 1
J 0
(2435 2060);
DISPLAY 0.617021 (2435 2060);
PAINT ORANGE (2435 2060);
FORCEPROP 2 LASTPIN (2425 2100) $PN 2
J 0
(2435 2110);
DISPLAY 0.617021 (2435 2110);
PAINT ORANGE (2435 2110);
FORCEPROP 2 LASTPIN (2325 1900) $PN 4
R 1
J 2
(2315 1890);
DISPLAY 0.617021 (2315 1890);
PAINT ORANGE (2315 1890);
FORCEADD RES..1
(1950 1775);
FORCEPROP 0 LAST ROOM HOT_SWAP
J 0
(1900 1975);
DISPLAY 1.021277 (1900 1975);
PAINT ORANGE (1900 1975);
DISPLAY INVISIBLE (1900 1975);
FORCEPROP 1 LAST PATH I60
J 0
(1900 1925);
DISPLAY 0.978723 (1900 1925);
PAINT WHITE (1900 1925);
DISPLAY INVISIBLE (1900 1925);
FORCEPROP 2 LAST CDS_LOCATION R1D48
J 0
(1900 1825);
DISPLAY 0.617021 (1900 1825);
PAINT AQUA (1900 1825);
DISPLAY INVISIBLE (1900 1825);
FORCEPROP 2 LAST SEC 1
J 0
(1900 1975);
DISPLAY 0.680851 (1900 1975);
PAINT MONO (1900 1975);
DISPLAY INVISIBLE (1900 1975);
FORCEPROP 2 LAST SEC_TYPE 0402
J 0
(1900 1975);
DISPLAY 1.021277 (1900 1975);
PAINT ORANGE (1900 1975);
DISPLAY INVISIBLE (1900 1975);
FORCEPROP 2 LAST CDS_LIB mstr_discrete
J 0
(1950 1775);
PAINT ORANGE (1950 1775);
DISPLAY INVISIBLE (1950 1775);
FORCEPROP 1 LAST PART_NUMBER G21796-066
J 0
(1900 1875);
DISPLAY 0.617021 (1900 1875);
PAINT BLUE (1900 1875);
FORCEPROP 1 LASTPIN (2050 1775) $PN 2
J 0
(2012 1787);
DISPLAY 0.617021 (2012 1787);
PAINT ORANGE (2012 1787);
FORCEPROP 1 LAST LOCATION R1D48
J 0
(1900 1825);
DISPLAY 0.617021 (1900 1825);
PAINT AQUA (1900 1825);
FORCEPROP 1 LAST TOLERANCE 1%
J 0
(2025 1725);
DISPLAY 0.617021 (2025 1725);
PAINT SKYBLUE (2025 1725);
FORCEPROP 1 LASTPIN (1850 1775) $PN 1
J 0
(1862 1787);
DISPLAY 0.617021 (1862 1787);
PAINT ORANGE (1862 1787);
FORCEPROP 1 LAST VALUE 10.0
J 2
(1975 1725);
DISPLAY 0.617021 (1975 1725);
PAINT SKYBLUE (1975 1725);
FORCEPROP 1 LAST PACK_TYPE 0402
J 0
(1725 1725);
DISPLAY 0.617021 (1725 1725);
PAINT SKYBLUE (1725 1725);
FORCEPROP 1 LAST MATERIAL CHIP
J 0
(1750 1625);
DISPLAY 0.617021 (1750 1625);
PAINT SKYBLUE (1750 1625);
FORCEPROP 1 LAST WATTAGE 1/16W
J 2
(1850 1675);
DISPLAY 0.617021 (1850 1675);
PAINT SKYBLUE (1850 1675);
FORCEADD P12V_STBY..1
(2525 3800);
FORCEPROP 3 LASTPIN (2525 3750) SIG_NAME P12V_STBY\g
J 0
(2535 3760);
DISPLAY 0.659574 (2535 3760);
PAINT MONO (2535 3760);
DISPLAY INVISIBLE (2535 3760);
FORCEPROP 1 LAST SIZE 1B
J 0
(2570 3822);
DISPLAY 0.340426 (2570 3822);
PAINT GREEN (2570 3822);
DISPLAY INVISIBLE (2570 3822);
FORCEPROP 1 LAST PATH I64
J 0
(2570 3802);
DISPLAY 0.340426 (2570 3802);
PAINT GREEN (2570 3802);
DISPLAY INVISIBLE (2570 3802);
FORCEPROP 2 LAST CDS_LIB mstr_symbols
J 0
(2525 3800);
PAINT ORANGE (2525 3800);
DISPLAY INVISIBLE (2525 3800);
FORCEPROP 1 LAST VOLTAGE 12.0V
J 0
(2480 3757);
DISPLAY 0.340426 (2480 3757);
PAINT SKYBLUE (2480 3757);
DISPLAY INVISIBLE (2480 3757);
FORCEPROP 1 LAST BODY_TYPE PLUMBING
J 0
(2480 3757);
DISPLAY 0.340426 (2480 3757);
PAINT GREEN (2480 3757);
DISPLAY INVISIBLE (2480 3757);
FORCEPROP 1 LAST HDL_POWER P12V_STBY
J 0
(2225 3675);
DISPLAY 0.872340 (2225 3675);
PAINT ORANGE (2225 3675);
DISPLAY INVISIBLE (2225 3675);
FORCEADD RES..2
(-4400 -400);
FORCEPROP 2 LAST SEC_TYPE 0402
J 0
(-4350 -175);
DISPLAY 1.021277 (-4350 -175);
PAINT ORANGE (-4350 -175);
DISPLAY INVISIBLE (-4350 -175);
FORCEPROP 2 LAST SEC 1
J 0
(-4350 -175);
DISPLAY 0.680851 (-4350 -175);
PAINT MONO (-4350 -175);
DISPLAY INVISIBLE (-4350 -175);
FORCEPROP 1 LAST PATH I70
J 0
(-4350 -225);
DISPLAY 0.978723 (-4350 -225);
PAINT WHITE (-4350 -225);
DISPLAY INVISIBLE (-4350 -225);
FORCEPROP 2 LAST ROOM HOT_SWAP
J 0
(-4350 -225);
DISPLAY 1.021277 (-4350 -225);
PAINT ORANGE (-4350 -225);
DISPLAY INVISIBLE (-4350 -225);
FORCEPROP 2 LAST CDS_LOCATION R9P19
J 0
(-4355 -275);
DISPLAY 0.617021 (-4355 -275);
PAINT AQUA (-4355 -275);
DISPLAY INVISIBLE (-4355 -275);
FORCEPROP 2 LAST CDS_LIB mstr_discrete
J 0
(-4400 -400);
PAINT ORANGE (-4400 -400);
DISPLAY INVISIBLE (-4400 -400);
FORCEPROP 1 LAST PART_NUMBER G21796-016
J 0
(-4360 -525);
DISPLAY 0.617021 (-4360 -525);
PAINT BLUE (-4360 -525);
FORCEPROP 1 LAST MATERIAL EMPTY
J 0
(-4360 -475);
DISPLAY 0.617021 (-4360 -475);
PAINT RED (-4360 -475);
FORCEPROP 1 LAST LOCATION R9P19
J 0
(-4355 -275);
DISPLAY 0.617021 (-4355 -275);
PAINT AQUA (-4355 -275);
FORCEPROP 1 LAST VALUE 10.0K
J 0
(-4355 -325);
DISPLAY 0.617021 (-4355 -325);
PAINT SKYBLUE (-4355 -325);
FORCEPROP 1 LAST TOLERANCE 1%
J 0
(-4355 -375);
DISPLAY 0.617021 (-4355 -375);
PAINT SKYBLUE (-4355 -375);
FORCEPROP 1 LAST WATTAGE 1/16W
J 0
(-4360 -425);
DISPLAY 0.617021 (-4360 -425);
PAINT SKYBLUE (-4360 -425);
FORCEPROP 1 LASTPIN (-4400 -300) $PN 1
J 0
(-4395 -338);
DISPLAY 0.617021 (-4395 -338);
PAINT ORANGE (-4395 -338);
FORCEPROP 1 LASTPIN (-4400 -500) $PN 2
J 0
(-4395 -490);
DISPLAY 0.617021 (-4395 -490);
PAINT ORANGE (-4395 -490);
FORCEPROP 1 LAST PACK_TYPE 0402
J 0
(-4360 -575);
DISPLAY 0.617021 (-4360 -575);
PAINT SKYBLUE (-4360 -575);
FORCEADD RES..2
(-4400 250);
FORCEPROP 2 LAST SEC_TYPE 0402
J 0
(-4350 475);
DISPLAY 1.021277 (-4350 475);
PAINT ORANGE (-4350 475);
DISPLAY INVISIBLE (-4350 475);
FORCEPROP 2 LAST ROOM HOT_SWAP
J 0
(-4350 425);
DISPLAY 1.021277 (-4350 425);
PAINT ORANGE (-4350 425);
DISPLAY INVISIBLE (-4350 425);
FORCEPROP 1 LAST PATH I71
J 0
(-4350 425);
DISPLAY 0.978723 (-4350 425);
PAINT WHITE (-4350 425);
DISPLAY INVISIBLE (-4350 425);
FORCEPROP 2 LAST SEC 1
J 0
(-4350 475);
DISPLAY 0.680851 (-4350 475);
PAINT MONO (-4350 475);
DISPLAY INVISIBLE (-4350 475);
FORCEPROP 2 LAST CDS_LOCATION R9P21
J 0
(-4355 375);
DISPLAY 0.617021 (-4355 375);
PAINT AQUA (-4355 375);
DISPLAY INVISIBLE (-4355 375);
FORCEPROP 2 LAST CDS_LIB mstr_discrete
J 0
(-4400 250);
PAINT ORANGE (-4400 250);
DISPLAY INVISIBLE (-4400 250);
FORCEPROP 1 LAST PART_NUMBER G21497-005
J 0
(-4360 125);
DISPLAY 0.617021 (-4360 125);
PAINT BLUE (-4360 125);
FORCEPROP 1 LAST TOLERANCE 5%
J 0
(-4355 275);
DISPLAY 0.617021 (-4355 275);
PAINT SKYBLUE (-4355 275);
FORCEPROP 1 LAST LOCATION R9P21
J 0
(-4355 375);
DISPLAY 0.617021 (-4355 375);
PAINT AQUA (-4355 375);
FORCEPROP 1 LAST VALUE 0.0
J 0
(-4355 325);
DISPLAY 0.617021 (-4355 325);
PAINT SKYBLUE (-4355 325);
FORCEPROP 1 LAST MATERIAL CHIP
J 0
(-4360 175);
DISPLAY 0.617021 (-4360 175);
PAINT SKYBLUE (-4360 175);
FORCEPROP 1 LAST WATTAGE 1/16W
J 0
(-4360 225);
DISPLAY 0.617021 (-4360 225);
PAINT SKYBLUE (-4360 225);
FORCEPROP 1 LASTPIN (-4400 350) $PN 1
J 0
(-4395 312);
DISPLAY 0.617021 (-4395 312);
PAINT ORANGE (-4395 312);
FORCEPROP 1 LAST PACK_TYPE 0402
J 0
(-4535 300);
DISPLAY 0.617021 (-4535 300);
PAINT SKYBLUE (-4535 300);
FORCEPROP 1 LASTPIN (-4400 150) $PN 2
J 0
(-4395 160);
DISPLAY 0.617021 (-4395 160);
PAINT ORANGE (-4395 160);
FORCEADD OFFPAGE..1
(-4700 525);
FORCEPROP 2 LAST CDS_LIB mstr_standard
J 0
(-4700 525);
PAINT ORANGE (-4700 525);
DISPLAY INVISIBLE (-4700 525);
FORCEPROP 2 LAST PATH I72
J 0
(-4950 575);
DISPLAY 1.021277 (-4950 575);
PAINT ORANGE (-4950 575);
DISPLAY INVISIBLE (-4950 575);
FORCEPROP 1 LAST OFFPAGE TRUE
J 0
(-4375 400);
DISPLAY 0.872340 (-4375 400);
PAINT GREEN (-4375 400);
DISPLAY INVISIBLE (-4375 400);
FORCEPROP 1 LAST COMMENT_BODY TRUE
J 0
(-4575 425);
DISPLAY 0.872340 (-4575 425);
PAINT GREEN (-4575 425);
DISPLAY INVISIBLE (-4575 425);
FORCEPROP 2 LAST $XR0 199 
J 0
(-4952 525);
DISPLAY 0.638298 (-4952 525);
PAINT MONO (-4952 525);
FORCEADD P3V3_STBY..1
(-3300 800);
FORCEPROP 3 LASTPIN (-3300 750) SIG_NAME P3V3_STBY\g
J 0
(-3290 760);
DISPLAY 0.659574 (-3290 760);
PAINT MONO (-3290 760);
DISPLAY INVISIBLE (-3290 760);
FORCEPROP 1 LAST PATH I78
J 0
(-3255 802);
DISPLAY 0.340426 (-3255 802);
PAINT GREEN (-3255 802);
DISPLAY INVISIBLE (-3255 802);
FORCEPROP 2 LAST CDS_LIB mstr_symbols
J 0
(-3300 800);
PAINT ORANGE (-3300 800);
DISPLAY INVISIBLE (-3300 800);
FORCEPROP 1 LAST SIZE 1B
J 0
(-3255 822);
DISPLAY 0.340426 (-3255 822);
PAINT GREEN (-3255 822);
DISPLAY INVISIBLE (-3255 822);
FORCEPROP 1 LAST VOLTAGE 3.3V
J 0
(-3345 757);
DISPLAY 0.340426 (-3345 757);
PAINT SKYBLUE (-3345 757);
DISPLAY INVISIBLE (-3345 757);
FORCEPROP 1 LAST BODY_TYPE PLUMBING
J 0
(-3345 757);
DISPLAY 0.340426 (-3345 757);
PAINT GREEN (-3345 757);
DISPLAY INVISIBLE (-3345 757);
FORCEPROP 1 LAST HDL_POWER P3V3_STBY
J 0
(-3600 675);
DISPLAY 0.872340 (-3600 675);
PAINT ORANGE (-3600 675);
DISPLAY INVISIBLE (-3600 675);
FORCEADD RES..2
(-3300 450);
FORCEPROP 2 LAST SEC 1
J 0
(-3250 675);
DISPLAY 0.680851 (-3250 675);
PAINT MONO (-3250 675);
DISPLAY INVISIBLE (-3250 675);
FORCEPROP 2 LAST SEC_TYPE 0402
J 0
(-3250 675);
DISPLAY 1.021277 (-3250 675);
PAINT ORANGE (-3250 675);
DISPLAY INVISIBLE (-3250 675);
FORCEPROP 2 LAST ROOM HOT_SWAP
J 0
(-3250 625);
DISPLAY 1.021277 (-3250 625);
PAINT ORANGE (-3250 625);
DISPLAY INVISIBLE (-3250 625);
FORCEPROP 1 LAST PATH I86
J 0
(-3250 625);
DISPLAY 0.978723 (-3250 625);
PAINT WHITE (-3250 625);
DISPLAY INVISIBLE (-3250 625);
FORCEPROP 2 LAST CDS_LOCATION R9P20
J 0
(-3255 575);
DISPLAY 0.617021 (-3255 575);
PAINT AQUA (-3255 575);
DISPLAY INVISIBLE (-3255 575);
FORCEPROP 2 LAST CDS_LIB mstr_discrete
J 0
(-3300 450);
PAINT ORANGE (-3300 450);
DISPLAY INVISIBLE (-3300 450);
FORCEPROP 1 LAST PART_NUMBER G21796-344
J 0
(-3260 325);
DISPLAY 0.617021 (-3260 325);
PAINT BLUE (-3260 325);
FORCEPROP 1 LAST PACK_TYPE 0402
J 0
(-3135 375);
DISPLAY 0.617021 (-3135 375);
PAINT SKYBLUE (-3135 375);
FORCEPROP 1 LAST MATERIAL CHIP
J 0
(-3260 375);
DISPLAY 0.617021 (-3260 375);
PAINT SKYBLUE (-3260 375);
FORCEPROP 1 LASTPIN (-3300 350) $PN 2
J 0
(-3295 360);
DISPLAY 0.617021 (-3295 360);
PAINT ORANGE (-3295 360);
FORCEPROP 1 LASTPIN (-3300 550) $PN 1
J 0
(-3295 512);
DISPLAY 0.617021 (-3295 512);
PAINT ORANGE (-3295 512);
FORCEPROP 1 LAST TOLERANCE 1%
J 0
(-3255 475);
DISPLAY 0.617021 (-3255 475);
PAINT SKYBLUE (-3255 475);
FORCEPROP 1 LAST WATTAGE 1/16W
J 0
(-3260 425);
DISPLAY 0.617021 (-3260 425);
PAINT SKYBLUE (-3260 425);
FORCEPROP 1 LAST VALUE 2.7K
J 0
(-3255 525);
DISPLAY 0.617021 (-3255 525);
PAINT SKYBLUE (-3255 525);
FORCEPROP 1 LAST LOCATION R9P20
J 0
(-3255 575);
DISPLAY 0.617021 (-3255 575);
PAINT AQUA (-3255 575);
FORCEADD OFFPAGE..2
(-2550 300);
FORCEPROP 2 LAST CDS_LIB mstr_standard
J 0
(-2550 300);
PAINT ORANGE (-2550 300);
DISPLAY INVISIBLE (-2550 300);
FORCEPROP 2 LAST PATH I92
J 0
(-2500 375);
DISPLAY 1.021277 (-2500 375);
PAINT ORANGE (-2500 375);
DISPLAY INVISIBLE (-2500 375);
FORCEPROP 1 LAST OFFPAGE TRUE
J 0
(-2225 175);
DISPLAY 0.872340 (-2225 175);
PAINT GREEN (-2225 175);
DISPLAY INVISIBLE (-2225 175);
FORCEPROP 1 LAST COMMENT_BODY TRUE
J 0
(-2595 205);
DISPLAY 0.872340 (-2595 205);
PAINT GREEN (-2595 205);
DISPLAY INVISIBLE (-2595 205);
FORCEPROP 2 LAST $XR1 145 
J 0
(-2241 300);
DISPLAY 0.638298 (-2241 300);
PAINT MONO (-2241 300);
FORCEPROP 2 LAST $XR2 170 
J 0
(-2121 300);
DISPLAY 0.638298 (-2121 300);
PAINT MONO (-2121 300);
FORCEPROP 2 LAST $XR0 120 
J 0
(-2361 300);
DISPLAY 0.638298 (-2361 300);
PAINT MONO (-2361 300);
FORCEADD OFFPAGE..1
(-4675 3675);
FORCEPROP 2 LAST CDS_LIB mstr_standard
J 0
(-4675 3675);
PAINT ORANGE (-4675 3675);
DISPLAY INVISIBLE (-4675 3675);
FORCEPROP 2 LAST PATH I94
J 0
(-4625 3750);
DISPLAY 1.021277 (-4625 3750);
PAINT ORANGE (-4625 3750);
DISPLAY INVISIBLE (-4625 3750);
FORCEPROP 1 LAST OFFPAGE TRUE
J 0
(-4350 3550);
DISPLAY 0.872340 (-4350 3550);
PAINT GREEN (-4350 3550);
DISPLAY INVISIBLE (-4350 3550);
FORCEPROP 1 LAST COMMENT_BODY TRUE
J 0
(-4550 3575);
DISPLAY 0.872340 (-4550 3575);
PAINT GREEN (-4550 3575);
DISPLAY INVISIBLE (-4550 3575);
FORCEPROP 2 LAST $XR0 199 
J 0
(-4957 3675);
DISPLAY 0.638298 (-4957 3675);
PAINT MONO (-4957 3675);
FORCEADD DNS..2
(-170 3420);
PAINT RED (-170 3420);
FORCEPROP 2 LAST CDS_LIB mstr_misc
J 0
(-170 3420);
PAINT ORANGE (-170 3420);
DISPLAY INVISIBLE (-170 3420);
FORCEPROP 1 LAST COMMENT_BODY TRUE
R 1
J 0
(-95 3195);
DISPLAY 0.872340 (-95 3195);
PAINT GREEN (-95 3195);
DISPLAY INVISIBLE (-95 3195);
FORCEADD DNS..2
(-1020 3420);
PAINT RED (-1020 3420);
FORCEPROP 2 LAST CDS_LIB mstr_misc
J 0
(-1020 3420);
PAINT ORANGE (-1020 3420);
DISPLAY INVISIBLE (-1020 3420);
FORCEPROP 1 LAST COMMENT_BODY TRUE
R 1
J 0
(-945 3195);
DISPLAY 0.872340 (-945 3195);
PAINT GREEN (-945 3195);
DISPLAY INVISIBLE (-945 3195);
FORCEADD DNS..2
(2755 3270);
PAINT RED (2755 3270);
FORCEPROP 2 LAST CDS_LIB mstr_misc
J 0
(2755 3270);
PAINT ORANGE (2755 3270);
DISPLAY INVISIBLE (2755 3270);
FORCEPROP 1 LAST COMMENT_BODY TRUE
R 1
J 0
(2830 3045);
DISPLAY 0.872340 (2830 3045);
PAINT GREEN (2830 3045);
DISPLAY INVISIBLE (2830 3045);
FORCEADD DNS..2
(-1895 3845);
PAINT RED (-1895 3845);
FORCEPROP 2 LAST CDS_LIB mstr_misc
J 0
(-1895 3845);
PAINT ORANGE (-1895 3845);
DISPLAY INVISIBLE (-1895 3845);
FORCEPROP 1 LAST COMMENT_BODY TRUE
R 1
J 0
(-1820 3620);
DISPLAY 0.872340 (-1820 3620);
PAINT GREEN (-1820 3620);
DISPLAY INVISIBLE (-1820 3620);
FORCEADD DNS..2
(-4395 -405);
PAINT RED (-4395 -405);
FORCEPROP 2 LAST CDS_LIB mstr_misc
J 0
(-4395 -405);
PAINT ORANGE (-4395 -405);
DISPLAY INVISIBLE (-4395 -405);
FORCEPROP 1 LAST COMMENT_BODY TRUE
R 1
J 0
(-4320 -630);
DISPLAY 0.872340 (-4320 -630);
PAINT GREEN (-4320 -630);
DISPLAY INVISIBLE (-4320 -630);
FORCEADD INTEL_CORP_BPAGE..1
(3000 -875);
FORCEPROP 1 LAST CDS_CON_LAST_MODIFIED Tue Dec 01 13:44:22 2015
J 0
(1575 -550);
PAINT GREEN (1575 -550);
DISPLAY INVISIBLE (1575 -550);
FORCEPROP 1 LAST CUSTOM_TXT_CDS <CURRENT_DESIGN_SHEET> OF <TOTAL_DESIGN_SHEETS>
J 0
(2500 -850);
PAINT ORANGE (2500 -850);
FORCEPROP 1 LAST CUSTOM_TXT_CDS <CON_LAST_MODIFIED>
J 0
(1075 -525);
PAINT ORANGE (1075 -525);
FORCEPROP 2 LAST CUSTOM_TXT_CDS <XR_PAGE_TITLE>
J 0
(-4890 4375);
DISPLAY 0.638298 (-4890 4375);
PAINT PINK (-4890 4375);
DISPLAY INVISIBLE (-4890 4375);
FORCEPROP 2 LAST CDS_XR_PAGE_TITLE CR-200 : @BASEBOARD_FAB2_LIB.BASEBOARD_FAB2(SCH_1):PAGE200
J 0
(-4890 4375);
DISPLAY 0.638298 (-4890 4375);
PAINT PINK (-4890 4375);
DISPLAY INVISIBLE (-4890 4375);
FORCEPROP 2 LAST ROOM S3_SWITCH
J 0
(2550 4275);
PAINT ORANGE (2550 4275);
DISPLAY INVISIBLE (2550 4275);
FORCEPROP 2 LAST CDS_LIB mstr_symbols
J 0
(3000 -875);
PAINT ORANGE (3000 -875);
DISPLAY INVISIBLE (3000 -875);
FORCEPROP 2 LAST PAGE_BORDER TRUE
J 0
(-4890 4375);
DISPLAY 1.021277 (-4890 4375);
PAINT PINK (-4890 4375);
DISPLAY INVISIBLE (-4890 4375);
FORCEPROP 2 LAST BOM_COST MISC_POWER
J 0
(-4875 4425);
DISPLAY 1.382979 (-4875 4425);
PAINT ORANGE (-4875 4425);
DISPLAY INVISIBLE (-4875 4425);
FORCEPROP 1 LAST COMMENT_BODY TRUE
J 0
(3012 -863);
DISPLAY 0.468085 (3012 -863);
PAINT GREEN (3012 -863);
DISPLAY INVISIBLE (3012 -863);
FORCEPROP 1 LAST SCH_ADDRESS1 2200 Mission College Blvd.
J 0
(-975 -750);
DISPLAY 0.617021 (-975 -750);
PAINT GREEN (-975 -750);
FORCEPROP 1 LAST SCH_REV 2.420
J 0
(2750 -725);
DISPLAY 0.978723 (2750 -725);
PAINT YELLOW (2750 -725);
FORCEPROP 1 LAST SCH_DEPT BESD
J 1
(-1450 -775);
DISPLAY 1.212766 (-1450 -775);
PAINT YELLOW (-1450 -775);
FORCEPROP 1 LAST SCH_NUMBER H4694802
J 0
(1700 -725);
DISPLAY 1.212766 (1700 -725);
PAINT YELLOW (1700 -725);
FORCEPROP 1 LAST SCH_ADDRESS3 Santa Clara, CA 95052-8119
J 0
(-975 -850);
DISPLAY 0.617021 (-975 -850);
PAINT GREEN (-975 -850);
FORCEPROP 1 LAST SCH_ADDRESS2 P.O. BOX 58119
J 0
(-975 -800);
DISPLAY 0.617021 (-975 -800);
PAINT GREEN (-975 -800);
FORCEPROP 1 LAST SCH_TITLE HOT SWAP CONTROLLER (2/2)
J 0
(-4950 -825);
DISPLAY 1.212766 (-4950 -825);
PAINT ORANGE (-4950 -825);
FORCEADD DNS..2
(-670 2995);
PAINT RED (-670 2995);
FORCEPROP 2 LAST CDS_LIB mstr_misc
J 0
(-670 2995);
PAINT ORANGE (-670 2995);
DISPLAY INVISIBLE (-670 2995);
FORCEPROP 1 LAST COMMENT_BODY TRUE
R 1
J 0
(-595 2770);
DISPLAY 0.872340 (-595 2770);
PAINT GREEN (-595 2770);
DISPLAY INVISIBLE (-595 2770);
WIRE 16 -1 (-1650 -425)(-1650 -250);
WIRE 16 -1 (-1650 475)(-1650 350);
WIRE 16 -1 (-3075 -425)(-3075 -300);
WIRE 16 -1 (-3075 -300)(-3125 -300);
WIRE 16 -1 (-1975 950)(-1975 975);
WIRE 16 -1 (-1125 950)(-1975 950);
WIRE 16 -1 (-1975 900)(-1975 950);
WIRE 16 -1 (-1125 450)(-1125 950);
WIRE 16 -1 (-825 950)(-1125 950);
WIRE 16 -1 (-825 875)(-825 950);
WIRE 16 -1 (-650 450)(-1125 450);
WIRE 16 -1 (-1975 75)(-1975 275);
WIRE 16 -1 (600 1350)(600 1200);
WIRE 16 -1 (900 1575)(900 1500);
WIRE 16 -1 (-1650 2450)(-1650 2475);
WIRE 16 -1 (550 -350)(550 -300);
WIRE 16 -1 (-4150 2350)(-4150 2200);
WIRE 16 -1 (-4575 2700)(-4575 2550);
WIRE 16 -1 (-2750 2975)(-2750 2850);
WIRE 16 -1 (-2800 2975)(-2750 2975);
WIRE 16 -1 (-3800 3650)(-3800 3600);
WIRE 16 -1 (-3650 3600)(-3800 3600);
WIRE 16 -1 (-3800 3525)(-3800 3600);
WIRE 16 -1 (-3650 3225)(-3650 3600);
WIRE 16 -1 (-3400 3225)(-3650 3225);
WIRE 16 -1 (-3800 3325)(-3800 3225);
WIRE 16 -1 (-2600 3725)(-2600 3825);
WIRE 16 -1 (-2825 3725)(-2600 3725);
WIRE 16 -1 (-2600 3625)(-2600 3725);
WIRE 16 -1 (-2825 3600)(-2825 3725);
WIRE 16 -1 (275 1175)(275 1350);
WIRE 16 -1 (-2150 3050)(-2150 3125);
WIRE 16 -1 (-3450 400)(-3450 275);
WIRE 16 -1 (-3500 1850)(-3500 1900);
WIRE 16 -1 (-3500 1100)(-3500 975);
WIRE 16 -1 (1750 325)(1750 400);
WIRE 16 -1 (1500 1350)(1500 1225);
WIRE 16 -1 (-4400 -600)(-4400 -500);
WIRE 16 -1 (-3950 -575)(-3950 -625);
WIRE 16 -1 (2750 3175)(2750 3050);
WIRE 16 -1 (-3950 650)(-3950 300);
WIRE 16 -1 (-1500 1475)(-1500 1350);
WIRE 16 -1 (-1950 1275)(-1950 1325);
WIRE 16 -1 (-1950 1925)(-1950 2000);
WIRE 16 -1 (-700 -200)(-700 -175);
WIRE 16 -1 (-1025 3325)(-1025 3275);
WIRE 16 -1 (-675 2900)(-675 2775);
WIRE 16 -1 (900 3775)(900 3650);
WIRE 16 -1 (900 3550)(900 3650);
WIRE 16 -1 (900 3650)(1025 3650);
WIRE 16 -1 (900 3250)(900 3550);
WIRE 16 -1 (900 3550)(1025 3550);
WIRE 16 -1 (900 3250)(900 3150);
WIRE 16 -1 (1025 3250)(900 3250);
WIRE 16 -1 (900 3150)(1025 3150);
WIRE 16 -1 (2525 3750)(2525 3700);
WIRE 16 -1 (2525 3425)(2525 3700);
WIRE 16 -1 (2525 3700)(2750 3700);
WIRE 16 -1 (2750 3700)(2750 3375);
WIRE 16 -1 (2525 3425)(2525 3375);
WIRE 16 -1 (2425 3425)(2525 3425);
WIRE 16 -1 (2525 3375)(2525 3325);
WIRE 16 -1 (2525 3375)(2425 3375);
WIRE 16 -1 (2525 3325)(2525 2875);
WIRE 16 -1 (2525 3325)(2425 3325);
WIRE 16 -1 (2525 2875)(2525 2825);
WIRE 16 -1 (2525 2875)(2450 2875);
WIRE 16 -1 (2525 2825)(2525 2775);
WIRE 16 -1 (2525 2825)(2450 2825);
WIRE 16 -1 (2525 2775)(2525 2150);
WIRE 16 -1 (2525 2775)(2450 2775);
WIRE 16 -1 (2525 2150)(2525 2100);
WIRE 16 -1 (2525 2150)(2425 2150);
WIRE 16 -1 (2525 2050)(2525 2100);
WIRE 16 -1 (2525 2100)(2425 2100);
WIRE 16 -1 (2525 2050)(2425 2050);
WIRE 16 -1 (-3300 750)(-3300 675);
WIRE 16 -1 (-3300 675)(-3450 675);
WIRE 16 -1 (-3300 675)(-3300 550);
WIRE 16 -1 (-3450 675)(-3800 675);
WIRE 16 -1 (-3450 600)(-3450 675);
WIRE 16 -1 (-3800 -50)(-3800 675);
WIRE 16 -1 (-3725 -50)(-3800 -50);
WIRE 16 -1 (-1050 -50)(-1050 100);
WIRE 16 -1 (-50 100)(-50 200);
WIRE 3 2175 (-1150 375)(-1150 -325);
WIRE 3 2175 (-1150 -325)(-350 -325);
WIRE 3 2175 (-1150 375)(-350 375);
WIRE 3 2175 (-350 375)(-350 -325);
WIRE 16 -1 (-1650 50)(-1650 150);
WIRE 16 -1 (-1650 -50)(-1650 50);
WIRE 16 -1 (-850 50)(-1650 50);
FORCEPROP 0 LAST SIG_NAME A_P12V_STBY_FP_TRIGGER
J 0
(-1622 47);
DISPLAY 0.617021 (-1622 47);
PAINT ORANGE (-1622 47);
FORCEPROP 2 LASTPROP $XR0 200 
J 0
(-1748 47);
DISPLAY 0.638298 (-1748 47);
PAINT MONO (-1748 47);
WIRE 16 -1 (-850 50)(-850 200);
WIRE 16 -1 (-700 200)(-650 200);
WIRE 16 -1 (-850 200)(-700 200);
WIRE 16 -1 (-700 -25)(-700 200);
WIRE 16 -1 (275 -200)(350 -200);
WIRE 16 -1 (275 975)(275 -200);
FORCEPROP 0 LAST SIG_NAME A_P12V_STBY_FPH_GATE
R 1
J 0
(253 -178);
DISPLAY 0.617021 (253 -178);
PAINT ORANGE (253 -178);
FORCEPROP 2 LASTPROP $XRERR UNIQUE?
J 0
(13 -178);
DISPLAY 0.638298 (13 -178);
PAINT MONO (13 -178);
DISPLAY INVISIBLE (13 -178);
WIRE 16 -1 (25 -200)(275 -200);
WIRE 16 -1 (-50 350)(25 350);
WIRE 16 -1 (25 350)(25 -200);
WIRE 16 -1 (600 1000)(600 900);
WIRE 16 -1 (600 900)(2475 900);
FORCEPROP 0 LAST SIG_NAME FM_UV_ADR_TRIGGER_N
J 0
(1840 910);
DISPLAY 0.617021 (1840 910);
PAINT ORANGE (1840 910);
WIRE 16 -1 (600 675)(600 900);
WIRE 16 -1 (900 675)(600 675);
WIRE 16 -1 (600 450)(600 675);
WIRE 16 -1 (-50 450)(600 450);
WIRE 16 -1 (-1975 600)(-1975 475);
WIRE 16 -1 (-1975 700)(-1975 600);
WIRE 16 -1 (-1975 600)(-1250 600);
FORCEPROP 0 LAST SIG_NAME A_P12V_STBY_ADR_TRIGGER
J 0
(-1947 622);
DISPLAY 0.617021 (-1947 622);
PAINT ORANGE (-1947 622);
FORCEPROP 2 LASTPROP $XRERR UNIQUE?
J 0
(-2187 622);
DISPLAY 0.638298 (-2187 622);
PAINT MONO (-2187 622);
DISPLAY INVISIBLE (-2187 622);
WIRE 16 -1 (-1250 600)(-1250 300);
WIRE 16 -1 (-1250 300)(-1050 300);
WIRE 16 -1 (-1050 250)(-1050 300);
WIRE 16 -1 (-1050 300)(-650 300);
WIRE 16 -1 (-1650 2225)(-2750 2225);
WIRE 16 -1 (-1650 2225)(-1650 2250);
WIRE 16 -1 (-1650 2225)(-1025 2225);
FORCEPROP 0 LAST SIG_NAME FM_OC_DETECT_N
J 0
(-1360 2235);
DISPLAY 0.617021 (-1360 2235);
PAINT ORANGE (-1360 2235);
WIRE 3 2175 (-2825 2125)(75 2125);
WIRE 3 2175 (75 2125)(75 1200);
WIRE 3 2175 (-2825 2125)(-2825 1200);
WIRE 3 2175 (-2825 1200)(75 1200);
WIRE 16 -1 (-1950 1525)(-1950 1575);
WIRE 16 -1 (-1950 1725)(-1950 1575);
WIRE 16 -1 (-1700 1575)(-1950 1575);
WIRE 16 -1 (-2300 1575)(-1950 1575);
FORCEPROP 2 LAST SIG_NAME BMC_UV_HIGH_SET
J 0
(-2310 1585);
DISPLAY 0.617021 (-2310 1585);
PAINT ORANGE (-2310 1585);
WIRE 16 -1 (-675 1950)(-75 1950);
FORCEPROP 0 LAST SIG_NAME A_P12V_STBY_FP_TRIGGER
J 0
(-422 1972);
DISPLAY 0.617021 (-422 1972);
PAINT ORANGE (-422 1972);
FORCEPROP 2 LASTPROP $XR0 200 
J 0
(235 1950);
DISPLAY 0.638298 (235 1950);
PAINT MONO (235 1950);
WIRE 16 -1 (-1500 1950)(-1500 1875);
WIRE 16 -1 (-925 1950)(-1500 1950);
FORCEPROP 2 LAST SIG_NAME UV_HIGH_SET_N
J 0
(-1485 1960);
DISPLAY 0.680851 (-1485 1960);
PAINT ORANGE (-1485 1960);
FORCEPROP 2 LASTPROP $XRERR UNIQUE?
J 0
(-1725 1960);
DISPLAY 0.638298 (-1725 1960);
PAINT MONO (-1725 1960);
DISPLAY INVISIBLE (-1725 1960);
WIRE 16 -1 (-2825 3400)(-2825 3300);
WIRE 16 -1 (-2825 3300)(-2750 3300);
WIRE 16 -1 (-2750 3300)(-2750 3125);
WIRE 16 -1 (-2800 3125)(-2750 3125);
WIRE 16 -1 (-1800 3850)(-1600 3850);
WIRE 16 -1 (-1600 2700)(-1600 3850);
WIRE 16 -1 (-2750 3125)(-2500 3125);
WIRE 16 -1 (-2500 3125)(-2500 2700);
WIRE 16 -1 (-2500 2700)(-1600 2700);
WIRE 16 -1 (-3300 2700)(-2500 2700);
WIRE 16 -1 (-3300 2700)(-3300 2225);
WIRE 16 -1 (-3150 2225)(-3300 2225);
WIRE 16 -1 (-3050 2225)(-3150 2225);
WIRE 16 -1 (-3150 2225)(-3150 2600);
FORCEPROP 0 LAST SIG_NAME IRQ_OC_DETECT_N
J 0
(-1622 2622);
DISPLAY 0.617021 (-1622 2622);
PAINT ORANGE (-1622 2622);
WIRE 16 -1 (-3150 2600)(-1025 2600);
WIRE 16 -1 (-3950 -200)(-3725 -200);
WIRE 16 -1 (-3950 100)(-3950 -200);
WIRE 16 -1 (-3950 -375)(-3950 -200);
FORCEPROP 0 LAST SIG_NAME A_HSC_INAP
R 1
J 0
(-3960 -265);
DISPLAY 0.617021 (-3960 -265);
PAINT ORANGE (-3960 -265);
FORCEPROP 2 LASTPROP $XRERR UNIQUE?
J 0
(-4200 -265);
DISPLAY 0.638298 (-4200 -265);
PAINT MONO (-4200 -265);
DISPLAY INVISIBLE (-4200 -265);
WIRE 16 -1 (-4150 -300)(-3725 -300);
WIRE 16 -1 (-4150 -125)(-4150 -300);
WIRE 16 -1 (-4150 -125)(-4400 -125);
FORCEPROP 2 LAST SIG_NAME A_HSC_TIMER_R
J 0
(-4385 -115);
DISPLAY 0.617021 (-4385 -115);
PAINT ORANGE (-4385 -115);
FORCEPROP 2 LASTPROP $XRERR UNIQUE?
J 0
(-4625 -115);
DISPLAY 0.638298 (-4625 -115);
PAINT MONO (-4625 -115);
DISPLAY INVISIBLE (-4625 -115);
WIRE 16 -1 (-4400 150)(-4400 -125);
WIRE 16 -1 (-4400 -300)(-4400 -125);
WIRE 16 -1 (-4400 525)(-4650 525);
FORCEPROP 2 LAST SIG_NAME A_HSC_TIMER
J 0
(-4660 535);
DISPLAY 0.617021 (-4660 535);
PAINT ORANGE (-4660 535);
WIRE 16 -1 (-4400 350)(-4400 525);
WIRE 16 -1 (-4575 3675)(-4625 3675);
FORCEPROP 0 LAST SIG_NAME A_HSC_CSOUT
J 0
(-4597 3697);
DISPLAY 0.617021 (-4597 3697);
PAINT ORANGE (-4597 3697);
WIRE 16 -1 (-4575 3500)(-4575 3675);
WIRE 16 -1 (-4150 2925)(-4150 3675);
WIRE 16 -1 (-4150 3675)(-4575 3675);
WIRE 16 -1 (-4575 3075)(-4575 3300);
WIRE 16 -1 (-3400 3075)(-4575 3075);
FORCEPROP 0 LAST SIG_NAME A_HSC_LOW
J 0
(-4547 3097);
DISPLAY 0.617021 (-4547 3097);
PAINT ORANGE (-4547 3097);
FORCEPROP 2 LASTPROP $XRERR UNIQUE?
J 0
(-4787 3097);
DISPLAY 0.638298 (-4787 3097);
PAINT MONO (-4787 3097);
DISPLAY INVISIBLE (-4787 3097);
WIRE 16 -1 (-4575 2900)(-4575 3075);
WIRE 16 -1 (-4150 2625)(-4150 2550);
WIRE 16 -1 (-4150 2725)(-4150 2625);
WIRE 16 -1 (-3800 2625)(-4150 2625);
WIRE 16 -1 (-3800 2625)(-3800 2975);
FORCEPROP 0 LAST SIG_NAME A_HSC_HIGH
J 0
(-3797 2972);
DISPLAY 0.617021 (-3797 2972);
PAINT ORANGE (-3797 2972);
FORCEPROP 2 LASTPROP $XRERR UNIQUE?
J 0
(-4037 2972);
DISPLAY 0.638298 (-4037 2972);
PAINT MONO (-4037 2972);
DISPLAY INVISIBLE (-4037 2972);
WIRE 16 -1 (-3800 2975)(-3400 2975);
WIRE 16 -1 (-2800 3225)(-2600 3225);
FORCEPROP 0 LAST SIG_NAME A_HSC_LOW_GATE
J 0
(-2722 3247);
DISPLAY 0.617021 (-2722 3247);
PAINT ORANGE (-2722 3247);
FORCEPROP 2 LASTPROP $XRERR UNIQUE?
J 0
(-2962 3247);
DISPLAY 0.638298 (-2962 3247);
PAINT MONO (-2962 3247);
DISPLAY INVISIBLE (-2962 3247);
WIRE 16 -1 (-2600 3225)(-2350 3225);
WIRE 16 -1 (-2600 3425)(-2600 3225);
WIRE 16 -1 (-1100 3150)(-675 3150);
FORCEPROP 0 LAST SIG_NAME A_HSC_MOP
J 0
(-1035 3110);
DISPLAY 0.617021 (-1035 3110);
PAINT ORANGE (-1035 3110);
WIRE 16 -1 (-675 3100)(-675 3150);
WIRE 16 -1 (-675 3150)(-175 3150);
WIRE 16 -1 (-175 3150)(125 3150);
WIRE 16 -1 (-175 3325)(-175 3150);
WIRE 16 -1 (-1025 3525)(-1025 3625);
WIRE 16 -1 (-1075 3625)(-1025 3625);
FORCEPROP 0 LAST SIG_NAME A_HSC_MON
J 0
(-1035 3635);
DISPLAY 0.617021 (-1035 3635);
PAINT ORANGE (-1035 3635);
WIRE 16 -1 (-1025 3625)(-175 3625);
WIRE 16 -1 (150 3625)(-175 3625);
WIRE 16 -1 (-175 3525)(-175 3625);
WIRE 16 -1 (2525 -50)(1750 -50);
FORCEPROP 0 LAST SIG_NAME IRQ_UV_DETECT_N
J 0
(1915 -40);
DISPLAY 0.617021 (1915 -40);
PAINT ORANGE (1915 -40);
WIRE 16 -1 (1750 125)(1750 -50);
WIRE 16 -1 (775 -50)(1750 -50);
WIRE 16 -1 (775 -50)(775 175);
WIRE 16 -1 (775 175)(950 175);
WIRE 16 -1 (550 175)(775 175);
WIRE 16 -1 (550 100)(550 175);
WIRE 16 -1 (900 1875)(900 1775);
WIRE 16 -1 (1250 1875)(900 1875);
FORCEPROP 0 LAST SIG_NAME A_HSC_C
J 0
(915 1885);
DISPLAY 0.617021 (915 1885);
PAINT ORANGE (915 1885);
FORCEPROP 2 LASTPROP $XRERR UNIQUE?
J 0
(675 1885);
DISPLAY 0.638298 (675 1885);
PAINT MONO (675 1885);
DISPLAY INVISIBLE (675 1885);
WIRE 16 -1 (750 3600)(1025 3600);
WIRE 16 -1 (750 2900)(750 3600);
FORCEPROP 0 LAST VOLTAGE +12V
J 0
(750 2950);
DISPLAY 1.021277 (750 2950);
PAINT SKYBLUE (750 2950);
DISPLAY INVISIBLE (750 2950);
FORCEPROP 0 LAST SIG_NAME P12V_HSC_SENP0
R 1
J 0
(740 2885);
DISPLAY 0.617021 (740 2885);
PAINT ORANGE (740 2885);
FORCEPROP 2 LASTPROP $XRERR UNIQUE?
J 0
(500 2885);
DISPLAY 0.638298 (500 2885);
PAINT MONO (500 2885);
DISPLAY INVISIBLE (500 2885);
WIRE 16 -1 (875 3200)(1025 3200);
FORCEPROP 0 LAST VOLTAGE +12V
J 0
(975 3250);
DISPLAY 1.021277 (975 3250);
PAINT SKYBLUE (975 3250);
DISPLAY INVISIBLE (975 3250);
WIRE 16 -1 (875 2900)(875 3200);
FORCEPROP 0 LAST SIG_NAME P12V_HSC_SENP1
R 1
J 0
(865 2885);
DISPLAY 0.617021 (865 2885);
PAINT ORANGE (865 2885);
FORCEPROP 2 LASTPROP $XRERR UNIQUE?
J 0
(625 2885);
DISPLAY 0.638298 (625 2885);
PAINT MONO (625 2885);
DISPLAY INVISIBLE (625 2885);
WIRE 16 -1 (1350 3200)(1225 3200);
WIRE 16 -1 (1350 2900)(1350 3200);
FORCEPROP 0 LAST VOLTAGE +12V
J 0
(1400 2975);
DISPLAY 1.021277 (1400 2975);
PAINT SKYBLUE (1400 2975);
DISPLAY INVISIBLE (1400 2975);
FORCEPROP 0 LAST SIG_NAME P12V_HSC_SENN1
R 1
J 0
(1390 2910);
DISPLAY 0.617021 (1390 2910);
PAINT ORANGE (1390 2910);
FORCEPROP 2 LASTPROP $XRERR UNIQUE?
J 0
(1150 2910);
DISPLAY 0.638298 (1150 2910);
PAINT MONO (1150 2910);
DISPLAY INVISIBLE (1150 2910);
WIRE 16 -1 (2325 1775)(2050 1775);
WIRE 16 -1 (2325 1900)(2325 1775);
FORCEPROP 0 LAST SIG_NAME A_HSC_GATE3_R
J 0
(2065 1785);
DISPLAY 0.617021 (2065 1785);
PAINT ORANGE (2065 1785);
FORCEPROP 2 LASTPROP $XRERR UNIQUE?
J 0
(1825 1785);
DISPLAY 0.638298 (1825 1785);
PAINT MONO (1825 1785);
DISPLAY INVISIBLE (1825 1785);
WIRE 16 -1 (2350 2525)(2100 2525);
FORCEPROP 0 LAST SIG_NAME A_HSC_GATE2_R
J 0
(2090 2535);
DISPLAY 0.617021 (2090 2535);
PAINT ORANGE (2090 2535);
FORCEPROP 2 LASTPROP $XRERR UNIQUE?
J 0
(1850 2535);
DISPLAY 0.638298 (1850 2535);
PAINT MONO (1850 2535);
DISPLAY INVISIBLE (1850 2535);
WIRE 16 -1 (2350 2625)(2350 2525);
WIRE 16 -1 (2325 3075)(2100 3075);
FORCEPROP 0 LAST SIG_NAME A_HSC_GATE1_R
J 0
(2090 3085);
DISPLAY 0.617021 (2090 3085);
PAINT ORANGE (2090 3085);
FORCEPROP 2 LASTPROP $XRERR UNIQUE?
J 0
(1850 3085);
DISPLAY 0.638298 (1850 3085);
PAINT MONO (1850 3085);
DISPLAY INVISIBLE (1850 3085);
WIRE 16 -1 (2325 3175)(2325 3075);
WIRE 16 -1 (-4325 1200)(-3700 1200);
FORCEPROP 2 LAST SIG_NAME FM_OC_DETECT_EN_N
J 0
(-4260 1210);
DISPLAY 0.617021 (-4260 1210);
PAINT ORANGE (-4260 1210);
WIRE 16 -1 (-2150 3850)(-2000 3850);
WIRE 16 -1 (-2150 3525)(-2150 3850);
FORCEPROP 0 LAST SIG_NAME A_HSC_LOW_DRAIN
R 1
J 0
(-2172 3522);
DISPLAY 0.617021 (-2172 3522);
PAINT ORANGE (-2172 3522);
FORCEPROP 2 LASTPROP $XRERR UNIQUE?
J 0
(-2412 3522);
DISPLAY 0.638298 (-2412 3522);
PAINT MONO (-2412 3522);
DISPLAY INVISIBLE (-2412 3522);
WIRE 16 -1 (-3125 -50)(-2600 -50);
FORCEPROP 2 LAST SIG_NAME PWRGD_DSW_PWROK
J 0
(-3060 -40);
DISPLAY 0.617021 (-3060 -40);
PAINT ORANGE (-3060 -40);
WIRE 16 -1 (1500 1025)(1500 675);
WIRE 16 -1 (2500 675)(1500 675);
FORCEPROP 0 LAST SIG_NAME FM_DISABLE_FAN_N
J 0
(1790 685);
DISPLAY 0.617021 (1790 685);
PAINT ORANGE (1790 685);
WIRE 16 -1 (1325 675)(1100 675);
WIRE 16 -1 (1500 675)(1325 675);
WIRE 16 -1 (1325 175)(1325 675);
WIRE 16 -1 (1150 175)(1325 175);
WIRE 16 -1 (1475 3600)(1225 3600);
WIRE 16 -1 (1475 2900)(1475 3600);
FORCEPROP 0 LAST VOLTAGE +12V
J 0
(1525 2975);
DISPLAY 1.021277 (1525 2975);
PAINT SKYBLUE (1525 2975);
DISPLAY INVISIBLE (1525 2975);
FORCEPROP 0 LAST SIG_NAME P12V_HSC_SENN0
R 1
J 0
(1515 2910);
DISPLAY 0.617021 (1515 2910);
PAINT ORANGE (1515 2910);
FORCEPROP 2 LASTPROP $XRERR UNIQUE?
J 0
(1275 2910);
DISPLAY 0.638298 (1275 2910);
PAINT MONO (1275 2910);
DISPLAY INVISIBLE (1275 2910);
WIRE 16 -1 (1225 3150)(1300 3150);
WIRE 16 -1 (1225 3650)(1300 3650);
WIRE 16 -1 (1225 3550)(1300 3550);
WIRE 16 -1 (1300 3650)(1300 3550);
WIRE 16 -1 (1225 3250)(1300 3250);
WIRE 16 -1 (1300 3150)(1300 3250);
WIRE 16 -1 (1300 3250)(1300 3325);
WIRE 16 -1 (1300 3550)(1300 3325);
WIRE 16 -1 (1300 3325)(1775 3325);
FORCEPROP 0 LAST VOLTAGE +12V
J 0
(1450 3400);
DISPLAY 1.021277 (1450 3400);
PAINT SKYBLUE (1450 3400);
DISPLAY INVISIBLE (1450 3400);
FORCEPROP 0 LAST SIG_NAME P12V_MB0_SW
J 0
(1440 3335);
DISPLAY 0.617021 (1440 3335);
PAINT ORANGE (1440 3335);
FORCEPROP 2 LASTPROP $XRERR UNIQUE?
J 0
(1200 3335);
DISPLAY 0.638298 (1200 3335);
PAINT MONO (1200 3335);
DISPLAY INVISIBLE (1200 3335);
WIRE 16 -1 (2125 3325)(1775 3325);
WIRE 16 -1 (1775 3325)(1775 2775);
WIRE 16 -1 (1775 2775)(2150 2775);
WIRE 16 -1 (1775 2775)(1775 2050);
WIRE 16 -1 (1775 2050)(2125 2050);
WIRE 16 -1 (1700 1775)(1850 1775);
WIRE 16 -1 (1450 1875)(1700 1875);
WIRE 16 -1 (1700 1875)(1700 1775);
WIRE 16 -1 (1700 2100)(1700 1875);
WIRE 16 -1 (1450 2100)(1700 2100);
FORCEPROP 0 LAST SIG_NAME A_HSC_GATE
J 0
(1440 2110);
DISPLAY 0.617021 (1440 2110);
PAINT ORANGE (1440 2110);
WIRE 16 -1 (1700 2100)(1700 2525);
WIRE 16 -1 (1900 2525)(1700 2525);
WIRE 16 -1 (1700 3075)(1700 2525);
WIRE 16 -1 (1900 3075)(1700 3075);
WIRE 16 -1 (350 3625)(500 3625);
WIRE 16 -1 (375 2250)(500 2250);
FORCEPROP 0 LAST SIG_NAME A_HSC_HSN
J 0
(615 2260);
DISPLAY 0.617021 (615 2260);
PAINT ORANGE (615 2260);
WIRE 16 -1 (500 3625)(500 2250);
WIRE 16 -1 (500 2250)(1475 2250);
WIRE 16 -1 (1350 2625)(1350 2700);
WIRE 16 -1 (1475 2625)(1475 2250);
WIRE 16 -1 (1475 2625)(1475 2700);
WIRE 16 -1 (1475 2625)(1350 2625);
WIRE 16 -1 (325 3150)(450 3150);
WIRE 16 -1 (375 2350)(450 2350);
FORCEPROP 0 LAST SIG_NAME A_HSC_HSP
J 0
(615 2360);
DISPLAY 0.617021 (615 2360);
PAINT ORANGE (615 2360);
WIRE 16 -1 (450 3150)(450 2350);
WIRE 16 -1 (450 2350)(875 2350);
WIRE 16 -1 (750 2625)(750 2700);
WIRE 16 -1 (875 2350)(875 2625);
WIRE 16 -1 (875 2625)(875 2700);
WIRE 16 -1 (875 2625)(750 2625);
WIRE 16 -1 (-3500 1500)(-3500 1550);
WIRE 16 -1 (-3500 1550)(-3500 1650);
WIRE 16 -1 (-3500 1550)(-2900 1550);
FORCEPROP 0 LAST SIG_NAME FM_OC_DETECT_EN
J 0
(-3275 1560);
DISPLAY 0.617021 (-3275 1560);
PAINT ORANGE (-3275 1560);
FORCEPROP 2 LASTPROP $XRERR UNIQUE?
J 0
(-3515 1560);
DISPLAY 0.638298 (-3515 1560);
PAINT MONO (-3515 1560);
DISPLAY INVISIBLE (-3515 1560);
WIRE 16 -1 (-2900 2125)(-2900 1550);
WIRE 16 -1 (-3125 -150)(-2650 -150);
WIRE 16 -1 (-2650 -150)(-2650 300);
WIRE 16 -1 (-2600 300)(-2650 300);
FORCEPROP 2 LAST SIG_NAME FM_HSC_TIMER_EXP_N
J 0
(-3035 310);
DISPLAY 0.617021 (-3035 310);
PAINT ORANGE (-3035 310);
WIRE 16 -1 (-3300 300)(-2650 300);
WIRE 16 -1 (-3300 350)(-3300 300);
DOT 1 (-1125 950);
DOT 1 (-3300 675);
DOT 1 (-1975 600);
DOT 1 (-4400 -125);
DOT 1 (-3950 -200);
DOT 1 (-4150 2625);
DOT 1 (-4575 3075);
DOT 1 (-4575 3675);
DOT 1 (-3450 675);
DOT 1 (-3500 1550);
DOT 1 (-2650 300);
DOT 1 (-3800 3600);
DOT 1 (-2750 3125);
DOT 1 (-2600 3225);
DOT 1 (-2600 3725);
DOT 1 (-1025 3625);
DOT 1 (-675 3150);
DOT 1 (-175 3150);
DOT 1 (-175 3625);
DOT 1 (1750 -50);
DOT 1 (775 175);
DOT 1 (600 675);
DOT 1 (600 900);
DOT 1 (1500 675);
DOT 1 (1325 675);
DOT 1 (1700 1875);
DOT 1 (500 2250);
DOT 1 (450 2350);
DOT 1 (875 2625);
DOT 1 (900 3250);
DOT 1 (900 3550);
DOT 1 (900 3650);
DOT 1 (1475 2625);
DOT 1 (1700 2100);
DOT 1 (1700 2525);
DOT 1 (1775 2775);
DOT 1 (1300 3325);
DOT 1 (1300 3250);
DOT 1 (1300 3550);
DOT 1 (1775 3325);
DOT 1 (2525 2100);
DOT 1 (2525 2150);
DOT 1 (2525 2775);
DOT 1 (2525 2825);
DOT 1 (2525 2875);
DOT 1 (2525 3325);
DOT 1 (2525 3375);
DOT 1 (2525 3425);
DOT 1 (2525 3700);
DOT 1 (-2500 2700);
DOT 1 (-1950 1575);
DOT 1 (-1650 2225);
DOT 1 (-3150 2225);
DOT 1 (275 -200);
DOT 1 (-700 200);
DOT 1 (-1650 50);
DOT 1 (-1050 300);
DOT 1 (-1975 950);
FORCENOTE
TP FAB1 ADD CAP 1117
(-1150 -400) 0;
DISPLAY LEFT (-1150 -400);
DISPLAY 1.021277 (-1150 -400);
PAINT RED (-1150 -400);
FORCENOTE
LOW VOLTAGE TIGGER CIRCUIT: FAST PROCHOT
(-1520 -525) 0;
DISPLAY LEFT (-1520 -525);
DISPLAY 1.595745 (-1520 -525);
PAINT PURPLE (-1520 -525);
FORCENOTE
IOUT FAST PROCHOT CIRCUIT
(-4945 3825) 0;
DISPLAY LEFT (-4945 3825);
DISPLAY 2.000000 (-4945 3825);
PAINT PURPLE (-4945 3825);
FORCENOTE
TRIP: 10.5V
(-1720 825) 0;
DISPLAY LEFT (-1720 825);
DISPLAY 1.595745 (-1720 825);
PAINT PURPLE (-1720 825);
FORCENOTE
ROOM: HOT_SWAP
(-4845 1650) 0;
DISPLAY LEFT (-4845 1650);
DISPLAY 1.021277 (-4845 1650);
PAINT PURPLE (-4845 1650);
FORCENOTE
LOW OC: 26.4A
(-4970 2275) 0;
DISPLAY LEFT (-4970 2275);
DISPLAY 1.595745 (-4970 2275);
PAINT PURPLE (-4970 2275);
FORCENOTE
P12V_PSU (12V INPUT POWER  FROM EXTERNAL PSU)
(95 3937) 0;
DISPLAY LEFT (95 3937);
DISPLAY 0.808511 (95 3937);
PAINT PURPLE (95 3937);
FORCENOTE
P12V_STBY (12V  STBY TO  THE BOARD)
(1970 3912) 0;
DISPLAY LEFT (1970 3912);
DISPLAY 0.808511 (1970 3912);
PAINT PURPLE (1970 3912);
FORCENOTE
HIGH OC: 36.8A
(-3720 2725) 0;
DISPLAY LEFT (-3720 2725);
DISPLAY 1.595745 (-3720 2725);
PAINT PURPLE (-3720 2725);
FORCENOTE
OCP LOW TRIP: 41.4A
(-2225 3975) 0;
DISPLAY LEFT (-2225 3975);
DISPLAY 0.808511 (-2225 3975);
PAINT PURPLE (-2225 3975);
FORCENOTE
HSC TIMER
(-4595 825) 0;
DISPLAY LEFT (-4595 825);
DISPLAY 2.000000 (-4595 825);
PAINT PURPLE (-4595 825);
FORCENOTE
INBN
(-975 1575) 0;
DISPLAY LEFT (-975 1575);
DISPLAY 0.851064 (-975 1575);
PAINT PURPLE (-975 1575);
FORCENOTE
DSW_PWROK FIRST TRIP POINT
(-3575 -600) 0;
DISPLAY LEFT (-3575 -600);
DISPLAY 1.021277 (-3575 -600);
PAINT PURPLE (-3575 -600);
FORCENOTE
8.3V NOMINAL ON P12V_STBY FAILING
(-3575 -675) 0;
DISPLAY LEFT (-3575 -675);
DISPLAY 1.021277 (-3575 -675);
PAINT PURPLE (-3575 -675);
FORCENOTE
INAP
(-975 1700) 0;
DISPLAY LEFT (-975 1700);
DISPLAY 0.851064 (-975 1700);
PAINT PURPLE (-975 1700);
FORCENOTE
TRIP: 11.5V
(-2320 -525) 0;
DISPLAY LEFT (-2320 -525);
DISPLAY 1.595745 (-2320 -525);
PAINT PURPLE (-2320 -525);
FORCENOTE
NOTE: GATE VOLTAGE: 24V PK
(1080 1625) 0;
DISPLAY LEFT (1080 1625);
DISPLAY 0.808511 (1080 1625);
PAINT PURPLE (1080 1625);
FORCENOTE
TRIP=10.5V
(-975 1625) 0;
DISPLAY LEFT (-975 1625);
DISPLAY 0.851064 (-975 1625);
PAINT PURPLE (-975 1625);
FORCENOTE
TP FAB1 R6W3 CHANGE TO 232K 1119
(-1200 1850) 0;
DISPLAY LEFT (-1200 1850);
DISPLAY 1.021277 (-1200 1850);
PAINT RED (-1200 1850);
FORCENOTE
UV_HIGH_SET=1 =>TRIP=11.5V(DEFAULT)
(-975 1525) 0;
DISPLAY LEFT (-975 1525);
DISPLAY 0.851064 (-975 1525);
PAINT PURPLE (-975 1525);
FORCENOTE
UV_HIGH_SET=0 => TRIP=11V
(-975 1475) 0;
DISPLAY LEFT (-975 1475);
DISPLAY 0.851064 (-975 1475);
PAINT PURPLE (-975 1475);
FORCENOTE
TP FAB1 ADD UV FPH VOLTAGE THRESHOLD SELECTION 1117
(-1650 1225) 0;
DISPLAY LEFT (-1650 1225);
DISPLAY 1.021277 (-1650 1225);
PAINT RED (-1650 1225);
FORCENOTE
LOW VOLTAGE TIGGER CIRCUIT: ADR TRIGGGER
(-1770 1000) 0;
DISPLAY LEFT (-1770 1000);
DISPLAY 1.021277 (-1770 1000);
PAINT PURPLE (-1770 1000);
QUIT
